FILE_TYPE = MACRO_DRAWING;
SET COLOR_WIRE YELLOW;
SET COLOR_PROP ORANGE;
SET COLOR_DOT WHITE;
SET COLOR_ARC YELLOW;
SET COLOR_BODY GREEN;
SET COLOR_NOTE PURPLE;
SET PROP_DISPLAY VALUE;
SET PAGE_NUMBER P75;
FORCEADD Q_CAP..1
(-4425 -2225);
FORCEPROP 1 LAST PART_NUMBER CH647KMEA04
J 0
(-4375 -2375);
DISPLAY 0.638298 (-4375 -2375);
DISPLAY INVISIBLE (-4375 -2375);
FORCEPROP 1 LAST VOLTAGE 4V
J 0
(-4375 -2225);
DISPLAY 0.638298 (-4375 -2225);
FORCEPROP 1 LAST TOLERANCE 20%
J 0
(-4375 -2275);
DISPLAY 0.638298 (-4375 -2275);
FORCEPROP 1 LAST PACK_TYPE C0805
J 0
(-4375 -2425);
DISPLAY 0.638298 (-4375 -2425);
FORCEPROP 1 LAST VALUE 47UF
J 0
(-4375 -2175);
DISPLAY 0.638298 (-4375 -2175);
FORCEPROP 1 LAST MATERIAL X6S
J 0
(-4375 -2325);
DISPLAY 0.638298 (-4375 -2325);
FORCEPROP 1 LAST $LOCATION C493
J 0
(-4375 -2125);
DISPLAY 0.978723 (-4375 -2125);
FORCEPROP 1 LASTPIN (-4425 -2125) $PN 1
J 0
(-4415 -2145);
DISPLAY 0.787234 (-4415 -2145);
FORCEPROP 1 LASTPIN (-4425 -2325) $PN 2
J 0
(-4415 -2345);
DISPLAY 0.787234 (-4415 -2345);
FORCEPROP 2 LAST CDS_LIB pure_quanta
J 0
(-4425 -2225);
PAINT MONO (-4425 -2225);
DISPLAY INVISIBLE (-4425 -2225);
FORCEPROP 2 LAST CDS_LOCATION C493
J 0
(-4375 -2025);
DISPLAY 1.021277 (-4375 -2025);
DISPLAY INVISIBLE (-4375 -2025);
FORCEPROP 2 LAST $SEC 1
J 0
(-4375 -2025);
DISPLAY 0.680851 (-4375 -2025);
PAINT MONO (-4375 -2025);
DISPLAY INVISIBLE (-4375 -2025);
FORCEPROP 2 LAST CDS_SEC 1
J 0
(-4375 -2025);
DISPLAY 1.021277 (-4375 -2025);
DISPLAY INVISIBLE (-4375 -2025);
FORCEPROP 1 LAST PATH I1
J 0
(-4375 -2075);
DISPLAY 0.978723 (-4375 -2075);
PAINT WHITE (-4375 -2075);
DISPLAY INVISIBLE (-4375 -2075);
FORCEADD UNIVERSAL_POWER..1
(-4425 -950);
FORCEPROP 3 LASTPIN (-4425 -1000) SIG_NAME PVCCINFAON_CPU0\g
J 0
(-4415 -990);
DISPLAY 0.659574 (-4415 -990);
PAINT MONO (-4415 -990);
DISPLAY INVISIBLE (-4415 -990);
FORCEPROP 1 LAST HDL_POWER PVCCINFAON_CPU0
J 1
(-4150 -900);
DISPLAY 0.872340 (-4150 -900);
PAINT GREEN (-4150 -900);
FORCEPROP 2 LAST CDS_LIB logical_power
J 0
(-4425 -950);
PAINT MONO (-4425 -950);
DISPLAY INVISIBLE (-4425 -950);
FORCEPROP 1 LAST PATH I10
J 0
(-4375 -925);
DISPLAY 0.872340 (-4375 -925);
PAINT AQUA (-4375 -925);
DISPLAY INVISIBLE (-4375 -925);
FORCEADD Q_CAP..1
(-4425 -250);
FORCEPROP 1 LAST PART_NUMBER CH647KMEA04
J 0
(-4375 -400);
DISPLAY 0.638298 (-4375 -400);
DISPLAY INVISIBLE (-4375 -400);
FORCEPROP 1 LAST PACK_TYPE C0805
J 0
(-4375 -450);
DISPLAY 0.638298 (-4375 -450);
FORCEPROP 1 LAST VALUE 47UF
J 0
(-4375 -200);
DISPLAY 0.638298 (-4375 -200);
FORCEPROP 1 LAST VOLTAGE 4V
J 0
(-4375 -250);
DISPLAY 0.638298 (-4375 -250);
FORCEPROP 1 LAST MATERIAL X6S
J 0
(-4375 -350);
DISPLAY 0.638298 (-4375 -350);
FORCEPROP 1 LAST TOLERANCE 20%
J 0
(-4375 -300);
DISPLAY 0.638298 (-4375 -300);
FORCEPROP 1 LAST $LOCATION C492
J 0
(-4375 -150);
DISPLAY 0.978723 (-4375 -150);
FORCEPROP 1 LASTPIN (-4425 -150) $PN 1
J 0
(-4415 -170);
DISPLAY 0.787234 (-4415 -170);
FORCEPROP 1 LASTPIN (-4425 -350) $PN 2
J 0
(-4415 -370);
DISPLAY 0.787234 (-4415 -370);
FORCEPROP 2 LAST CDS_LIB pure_quanta
J 0
(-4425 -250);
PAINT MONO (-4425 -250);
DISPLAY INVISIBLE (-4425 -250);
FORCEPROP 2 LAST CDS_LOCATION C492
J 0
(-4375 -50);
DISPLAY 1.021277 (-4375 -50);
DISPLAY INVISIBLE (-4375 -50);
FORCEPROP 2 LAST $SEC 1
J 0
(-4375 -50);
DISPLAY 0.680851 (-4375 -50);
PAINT MONO (-4375 -50);
DISPLAY INVISIBLE (-4375 -50);
FORCEPROP 2 LAST CDS_SEC 1
J 0
(-4375 -50);
DISPLAY 1.021277 (-4375 -50);
DISPLAY INVISIBLE (-4375 -50);
FORCEPROP 1 LAST PATH I11
J 0
(-4375 -100);
DISPLAY 0.978723 (-4375 -100);
PAINT WHITE (-4375 -100);
DISPLAY INVISIBLE (-4375 -100);
FORCEADD UNIVERSAL_POWER..1
(-4425 25);
FORCEPROP 3 LASTPIN (-4425 -25) SIG_NAME PVCCFA_EHV_CPU0\g
J 0
(-4415 -15);
DISPLAY 0.659574 (-4415 -15);
PAINT MONO (-4415 -15);
DISPLAY INVISIBLE (-4415 -15);
FORCEPROP 1 LAST HDL_POWER PVCCFA_EHV_CPU0
J 1
(-4150 75);
DISPLAY 0.872340 (-4150 75);
PAINT GREEN (-4150 75);
FORCEPROP 2 LAST CDS_LIB logical_power
J 0
(-4425 25);
PAINT MONO (-4425 25);
DISPLAY INVISIBLE (-4425 25);
FORCEPROP 1 LAST PATH I12
J 0
(-4375 50);
DISPLAY 0.872340 (-4375 50);
PAINT AQUA (-4375 50);
DISPLAY INVISIBLE (-4375 50);
FORCEADD Q_CAP..1
(-4425 725);
FORCEPROP 1 LAST PART_NUMBER CH647KMEA04
J 0
(-4375 575);
DISPLAY 0.638298 (-4375 575);
DISPLAY INVISIBLE (-4375 575);
FORCEPROP 1 LAST VALUE 47UF
J 0
(-4375 775);
DISPLAY 0.638298 (-4375 775);
FORCEPROP 1 LAST VOLTAGE 4V
J 0
(-4375 725);
DISPLAY 0.638298 (-4375 725);
FORCEPROP 1 LAST TOLERANCE 20%
J 0
(-4375 675);
DISPLAY 0.638298 (-4375 675);
FORCEPROP 1 LAST PACK_TYPE C0805
J 0
(-4375 525);
DISPLAY 0.638298 (-4375 525);
FORCEPROP 1 LAST MATERIAL X6S
J 0
(-4375 625);
DISPLAY 0.638298 (-4375 625);
FORCEPROP 1 LAST $LOCATION C491
J 0
(-4375 825);
DISPLAY 0.978723 (-4375 825);
FORCEPROP 1 LASTPIN (-4425 825) $PN 1
J 0
(-4415 805);
DISPLAY 0.787234 (-4415 805);
FORCEPROP 1 LASTPIN (-4425 625) $PN 2
J 0
(-4415 605);
DISPLAY 0.787234 (-4415 605);
FORCEPROP 2 LAST CDS_LIB pure_quanta
J 0
(-4425 725);
PAINT MONO (-4425 725);
DISPLAY INVISIBLE (-4425 725);
FORCEPROP 2 LAST CDS_LOCATION C491
J 0
(-4375 925);
DISPLAY 1.021277 (-4375 925);
DISPLAY INVISIBLE (-4375 925);
FORCEPROP 2 LAST $SEC 1
J 0
(-4375 925);
DISPLAY 0.680851 (-4375 925);
PAINT MONO (-4375 925);
DISPLAY INVISIBLE (-4375 925);
FORCEPROP 2 LAST CDS_SEC 1
J 0
(-4375 925);
DISPLAY 1.021277 (-4375 925);
DISPLAY INVISIBLE (-4375 925);
FORCEPROP 1 LAST PATH I13
J 0
(-4375 875);
DISPLAY 0.978723 (-4375 875);
PAINT WHITE (-4375 875);
DISPLAY INVISIBLE (-4375 875);
FORCEADD Q_CAP..1
(-3975 -1225);
FORCEPROP 1 LAST PART_NUMBER CH647LME900
J 0
(-3925 -1375);
DISPLAY 0.638298 (-3925 -1375);
DISPLAY INVISIBLE (-3925 -1375);
FORCEPROP 1 LAST VOLTAGE 2.5V
J 0
(-3925 -1225);
DISPLAY 0.638298 (-3925 -1225);
FORCEPROP 1 LAST MATERIAL X6S
J 0
(-3925 -1325);
DISPLAY 0.638298 (-3925 -1325);
FORCEPROP 1 LAST PACK_TYPE C0603
J 0
(-3925 -1425);
DISPLAY 0.638298 (-3925 -1425);
FORCEPROP 1 LAST VALUE 47UF
J 0
(-3925 -1175);
DISPLAY 0.638298 (-3925 -1175);
FORCEPROP 1 LAST TOLERANCE 20%
J 0
(-3925 -1275);
DISPLAY 0.638298 (-3925 -1275);
FORCEPROP 1 LAST $LOCATION C532
J 0
(-3925 -1125);
DISPLAY 0.978723 (-3925 -1125);
FORCEPROP 1 LASTPIN (-3975 -1125) $PN 1
J 0
(-3965 -1145);
DISPLAY 0.787234 (-3965 -1145);
FORCEPROP 1 LASTPIN (-3975 -1325) $PN 2
J 0
(-3965 -1345);
DISPLAY 0.787234 (-3965 -1345);
FORCEPROP 2 LAST CDS_LIB pure_quanta
J 0
(-3975 -1225);
PAINT MONO (-3975 -1225);
DISPLAY INVISIBLE (-3975 -1225);
FORCEPROP 2 LAST CDS_LOCATION C532
J 0
(-3925 -1025);
DISPLAY 1.021277 (-3925 -1025);
DISPLAY INVISIBLE (-3925 -1025);
FORCEPROP 2 LAST $SEC 1
J 0
(-3925 -1025);
DISPLAY 0.680851 (-3925 -1025);
PAINT MONO (-3925 -1025);
DISPLAY INVISIBLE (-3925 -1025);
FORCEPROP 2 LAST CDS_SEC 1
J 0
(-3925 -1025);
DISPLAY 1.021277 (-3925 -1025);
DISPLAY INVISIBLE (-3925 -1025);
FORCEPROP 1 LAST PATH I14
J 0
(-3925 -1075);
DISPLAY 0.978723 (-3925 -1075);
PAINT WHITE (-3925 -1075);
DISPLAY INVISIBLE (-3925 -1075);
FORCEADD UNIVERSAL_GND..1
(-3975 -600);
FORCEPROP 3 LASTPIN (-3975 -550) SIG_NAME GND\g
J 0
(-3965 -540);
DISPLAY 0.659574 (-3965 -540);
PAINT MONO (-3965 -540);
DISPLAY INVISIBLE (-3965 -540);
FORCEPROP 2 LAST CDS_LIB logical_power
J 0
(-3975 -600);
PAINT MONO (-3975 -600);
DISPLAY INVISIBLE (-3975 -600);
FORCEPROP 1 LAST HDL_POWER GND
J 1
(-3950 -675);
DISPLAY 0.872340 (-3950 -675);
PAINT GREEN (-3950 -675);
DISPLAY INVISIBLE (-3950 -675);
FORCEPROP 1 LAST PATH I15
J 0
(-3900 -600);
DISPLAY 0.872340 (-3900 -600);
PAINT AQUA (-3900 -600);
DISPLAY INVISIBLE (-3900 -600);
FORCEADD Q_CAP..1
(-3975 -250);
FORCEPROP 1 LAST PART_NUMBER CH647KMEA04
J 0
(-3925 -400);
DISPLAY 0.638298 (-3925 -400);
DISPLAY INVISIBLE (-3925 -400);
FORCEPROP 1 LAST PACK_TYPE C0805
J 0
(-3925 -450);
DISPLAY 0.638298 (-3925 -450);
FORCEPROP 1 LAST VALUE 47UF
J 0
(-3925 -200);
DISPLAY 0.638298 (-3925 -200);
FORCEPROP 1 LAST VOLTAGE 4V
J 0
(-3925 -250);
DISPLAY 0.638298 (-3925 -250);
FORCEPROP 1 LAST MATERIAL X6S
J 0
(-3925 -350);
DISPLAY 0.638298 (-3925 -350);
FORCEPROP 1 LAST TOLERANCE 20%
J 0
(-3925 -300);
DISPLAY 0.638298 (-3925 -300);
FORCEPROP 1 LAST $LOCATION C496
J 0
(-3925 -150);
DISPLAY 0.978723 (-3925 -150);
FORCEPROP 1 LASTPIN (-3975 -150) $PN 1
J 0
(-3965 -170);
DISPLAY 0.787234 (-3965 -170);
FORCEPROP 1 LASTPIN (-3975 -350) $PN 2
J 0
(-3965 -370);
DISPLAY 0.787234 (-3965 -370);
FORCEPROP 2 LAST CDS_LIB pure_quanta
J 0
(-3975 -250);
PAINT MONO (-3975 -250);
DISPLAY INVISIBLE (-3975 -250);
FORCEPROP 2 LAST CDS_LOCATION C496
J 0
(-3925 -50);
DISPLAY 1.021277 (-3925 -50);
DISPLAY INVISIBLE (-3925 -50);
FORCEPROP 2 LAST $SEC 1
J 0
(-3925 -50);
DISPLAY 0.680851 (-3925 -50);
PAINT MONO (-3925 -50);
DISPLAY INVISIBLE (-3925 -50);
FORCEPROP 2 LAST CDS_SEC 1
J 0
(-3925 -50);
DISPLAY 1.021277 (-3925 -50);
DISPLAY INVISIBLE (-3925 -50);
FORCEPROP 1 LAST PATH I16
J 0
(-3925 -100);
DISPLAY 0.978723 (-3925 -100);
PAINT WHITE (-3925 -100);
DISPLAY INVISIBLE (-3925 -100);
FORCEADD Q_CAP..1
(-3525 -1225);
FORCEPROP 1 LAST PART_NUMBER CH647LME900
J 0
(-3475 -1375);
DISPLAY 0.638298 (-3475 -1375);
DISPLAY INVISIBLE (-3475 -1375);
FORCEPROP 1 LAST TOLERANCE 20%
J 0
(-3475 -1275);
DISPLAY 0.638298 (-3475 -1275);
FORCEPROP 1 LAST VOLTAGE 2.5V
J 0
(-3475 -1225);
DISPLAY 0.638298 (-3475 -1225);
FORCEPROP 1 LAST MATERIAL X6S
J 0
(-3475 -1325);
DISPLAY 0.638298 (-3475 -1325);
FORCEPROP 1 LAST PACK_TYPE C0603
J 0
(-3475 -1425);
DISPLAY 0.638298 (-3475 -1425);
FORCEPROP 1 LAST VALUE 47UF
J 0
(-3475 -1175);
DISPLAY 0.638298 (-3475 -1175);
FORCEPROP 1 LAST $LOCATION C533
J 0
(-3475 -1125);
DISPLAY 0.978723 (-3475 -1125);
FORCEPROP 1 LASTPIN (-3525 -1125) $PN 1
J 0
(-3515 -1145);
DISPLAY 0.787234 (-3515 -1145);
FORCEPROP 1 LASTPIN (-3525 -1325) $PN 2
J 0
(-3515 -1345);
DISPLAY 0.787234 (-3515 -1345);
FORCEPROP 2 LAST CDS_LIB pure_quanta
J 0
(-3525 -1225);
PAINT MONO (-3525 -1225);
DISPLAY INVISIBLE (-3525 -1225);
FORCEPROP 2 LAST CDS_LOCATION C533
J 0
(-3475 -1025);
DISPLAY 1.021277 (-3475 -1025);
DISPLAY INVISIBLE (-3475 -1025);
FORCEPROP 2 LAST $SEC 1
J 0
(-3475 -1025);
DISPLAY 0.680851 (-3475 -1025);
PAINT MONO (-3475 -1025);
DISPLAY INVISIBLE (-3475 -1025);
FORCEPROP 2 LAST CDS_SEC 1
J 0
(-3475 -1025);
DISPLAY 1.021277 (-3475 -1025);
DISPLAY INVISIBLE (-3475 -1025);
FORCEPROP 1 LAST PATH I17
J 0
(-3475 -1075);
DISPLAY 0.978723 (-3475 -1075);
PAINT WHITE (-3475 -1075);
DISPLAY INVISIBLE (-3475 -1075);
FORCEADD Q_CAP..1
(-3975 725);
FORCEPROP 1 LAST PART_NUMBER CH647KMEA04
J 0
(-3925 575);
DISPLAY 0.638298 (-3925 575);
DISPLAY INVISIBLE (-3925 575);
FORCEPROP 1 LAST VALUE 47UF
J 0
(-3925 775);
DISPLAY 0.638298 (-3925 775);
FORCEPROP 1 LAST VOLTAGE 4V
J 0
(-3925 725);
DISPLAY 0.638298 (-3925 725);
FORCEPROP 1 LAST TOLERANCE 20%
J 0
(-3925 675);
DISPLAY 0.638298 (-3925 675);
FORCEPROP 1 LAST PACK_TYPE C0805
J 0
(-3925 525);
DISPLAY 0.638298 (-3925 525);
FORCEPROP 1 LAST MATERIAL X6S
J 0
(-3925 625);
DISPLAY 0.638298 (-3925 625);
FORCEPROP 1 LAST $LOCATION C495
J 0
(-3925 825);
DISPLAY 0.978723 (-3925 825);
FORCEPROP 1 LASTPIN (-3975 825) $PN 1
J 0
(-3965 805);
DISPLAY 0.787234 (-3965 805);
FORCEPROP 1 LASTPIN (-3975 625) $PN 2
J 0
(-3965 605);
DISPLAY 0.787234 (-3965 605);
FORCEPROP 2 LAST CDS_LIB pure_quanta
J 0
(-3975 725);
PAINT MONO (-3975 725);
DISPLAY INVISIBLE (-3975 725);
FORCEPROP 2 LAST CDS_LOCATION C495
J 0
(-3925 925);
DISPLAY 1.021277 (-3925 925);
DISPLAY INVISIBLE (-3925 925);
FORCEPROP 2 LAST $SEC 1
J 0
(-3925 925);
DISPLAY 0.680851 (-3925 925);
PAINT MONO (-3925 925);
DISPLAY INVISIBLE (-3925 925);
FORCEPROP 2 LAST CDS_SEC 1
J 0
(-3925 925);
DISPLAY 1.021277 (-3925 925);
DISPLAY INVISIBLE (-3925 925);
FORCEPROP 1 LAST PATH I18
J 0
(-3925 875);
DISPLAY 0.978723 (-3925 875);
PAINT WHITE (-3925 875);
DISPLAY INVISIBLE (-3925 875);
FORCEADD Q_CAP..1
(-3525 725);
FORCEPROP 1 LAST PART_NUMBER CH647KMEA04
J 0
(-3475 575);
DISPLAY 0.638298 (-3475 575);
DISPLAY INVISIBLE (-3475 575);
FORCEPROP 1 LAST VALUE 47UF
J 0
(-3475 775);
DISPLAY 0.638298 (-3475 775);
FORCEPROP 1 LAST VOLTAGE 4V
J 0
(-3475 725);
DISPLAY 0.638298 (-3475 725);
FORCEPROP 1 LAST TOLERANCE 20%
J 0
(-3475 675);
DISPLAY 0.638298 (-3475 675);
FORCEPROP 1 LAST PACK_TYPE C0805
J 0
(-3475 525);
DISPLAY 0.638298 (-3475 525);
FORCEPROP 1 LAST MATERIAL X6S
J 0
(-3475 625);
DISPLAY 0.638298 (-3475 625);
FORCEPROP 1 LAST $LOCATION C515
J 0
(-3475 825);
DISPLAY 0.978723 (-3475 825);
FORCEPROP 1 LASTPIN (-3525 825) $PN 1
J 0
(-3515 805);
DISPLAY 0.787234 (-3515 805);
PAINT MONO (-3515 805);
FORCEPROP 1 LASTPIN (-3525 625) $PN 2
J 0
(-3515 605);
DISPLAY 0.787234 (-3515 605);
PAINT MONO (-3515 605);
FORCEPROP 2 LAST CDS_LIB pure_quanta
J 0
(-3525 725);
DISPLAY INVISIBLE (-3525 725);
FORCEPROP 2 LAST CDS_LOCATION C515
J 0
(-3475 925);
DISPLAY 1.021277 (-3475 925);
DISPLAY INVISIBLE (-3475 925);
FORCEPROP 0 LAST $SEC 1
J 0
(-3475 875);
DISPLAY 0.680851 (-3475 875);
PAINT MONO (-3475 875);
DISPLAY INVISIBLE (-3475 875);
FORCEPROP 2 LAST CDS_SEC 1
J 0
(-3475 925);
DISPLAY 1.021277 (-3475 925);
DISPLAY INVISIBLE (-3475 925);
FORCEPROP 1 LAST PATH I19
J 0
(-3475 875);
DISPLAY 0.978723 (-3475 875);
PAINT WHITE (-3475 875);
DISPLAY INVISIBLE (-3475 875);
FORCEADD UNIVERSAL_POWER..1
(-4425 -1950);
FORCEPROP 3 LASTPIN (-4425 -2000) SIG_NAME PVCCFA_EHV_FIVRA_CPU0\g
J 0
(-4415 -1990);
DISPLAY 0.659574 (-4415 -1990);
PAINT MONO (-4415 -1990);
DISPLAY INVISIBLE (-4415 -1990);
FORCEPROP 1 LAST HDL_POWER PVCCFA_EHV_FIVRA_CPU0
J 1
(-4025 -1900);
DISPLAY 0.872340 (-4025 -1900);
PAINT GREEN (-4025 -1900);
FORCEPROP 2 LAST CDS_LIB logical_power
J 0
(-4425 -1950);
DISPLAY INVISIBLE (-4425 -1950);
FORCEPROP 1 LAST PATH I2
J 0
(-4375 -1925);
DISPLAY 0.872340 (-4375 -1925);
PAINT AQUA (-4375 -1925);
DISPLAY INVISIBLE (-4375 -1925);
FORCEADD UNIVERSAL_POWER..1
(-4425 1000);
FORCEPROP 3 LASTPIN (-4425 950) SIG_NAME PVCCD_HV_CPU0\g
J 0
(-4415 960);
DISPLAY 0.659574 (-4415 960);
PAINT MONO (-4415 960);
DISPLAY INVISIBLE (-4415 960);
FORCEPROP 1 LAST HDL_POWER PVCCD_HV_CPU0
J 1
(-4200 1050);
DISPLAY 0.872340 (-4200 1050);
PAINT GREEN (-4200 1050);
FORCEPROP 2 LAST CDS_LIB logical_power
J 0
(-4425 1000);
PAINT MONO (-4425 1000);
DISPLAY INVISIBLE (-4425 1000);
FORCEPROP 1 LAST PATH I20
J 0
(-4375 1025);
DISPLAY 0.872340 (-4375 1025);
PAINT AQUA (-4375 1025);
DISPLAY INVISIBLE (-4375 1025);
FORCEADD Q_CAP..1
(-4425 1725);
FORCEPROP 1 LAST PART_NUMBER CH647KMEA04
J 0
(-4375 1575);
DISPLAY 0.638298 (-4375 1575);
DISPLAY INVISIBLE (-4375 1575);
FORCEPROP 1 LAST VALUE 47UF
J 0
(-4375 1775);
DISPLAY 0.638298 (-4375 1775);
FORCEPROP 1 LAST VOLTAGE 4V
J 0
(-4375 1725);
DISPLAY 0.638298 (-4375 1725);
FORCEPROP 1 LAST TOLERANCE 20%
J 0
(-4375 1675);
DISPLAY 0.638298 (-4375 1675);
FORCEPROP 1 LAST PACK_TYPE C0805
J 0
(-4375 1525);
DISPLAY 0.638298 (-4375 1525);
FORCEPROP 1 LAST MATERIAL X6S
J 0
(-4375 1625);
DISPLAY 0.638298 (-4375 1625);
FORCEPROP 1 LAST $LOCATION C356
J 0
(-4375 1825);
DISPLAY 0.638298 (-4375 1825);
FORCEPROP 1 LASTPIN (-4425 1825) $PN 1
J 0
(-4415 1805);
DISPLAY 0.787234 (-4415 1805);
FORCEPROP 1 LASTPIN (-4425 1625) $PN 2
J 0
(-4415 1605);
DISPLAY 0.787234 (-4415 1605);
FORCEPROP 2 LAST CDS_LIB pure_quanta
J 0
(-4425 1725);
PAINT MONO (-4425 1725);
DISPLAY INVISIBLE (-4425 1725);
FORCEPROP 1 LAST $LOCATION C356
J 0
(-4375 1925);
DISPLAY 1.021277 (-4375 1925);
DISPLAY INVISIBLE (-4375 1925);
FORCEPROP 2 LAST CDS_LOCATION C356
J 0
(-4375 1925);
DISPLAY 1.021277 (-4375 1925);
DISPLAY INVISIBLE (-4375 1925);
FORCEPROP 2 LAST $SEC 1
J 0
(-4375 1925);
DISPLAY 0.680851 (-4375 1925);
PAINT MONO (-4375 1925);
DISPLAY INVISIBLE (-4375 1925);
FORCEPROP 2 LAST CDS_SEC 1
J 0
(-4375 1925);
DISPLAY 1.021277 (-4375 1925);
DISPLAY INVISIBLE (-4375 1925);
FORCEPROP 1 LAST PATH I21
J 0
(-4375 1875);
DISPLAY 0.978723 (-4375 1875);
PAINT WHITE (-4375 1875);
DISPLAY INVISIBLE (-4375 1875);
FORCEADD UNIVERSAL_POWER..1
(-4425 2000);
FORCEPROP 3 LASTPIN (-4425 1950) SIG_NAME PVCCIN_CPU0\g
J 0
(-4415 1960);
DISPLAY 0.659574 (-4415 1960);
PAINT MONO (-4415 1960);
DISPLAY INVISIBLE (-4415 1960);
FORCEPROP 1 LAST HDL_POWER PVCCIN_CPU0
J 1
(-4225 2050);
DISPLAY 0.872340 (-4225 2050);
PAINT GREEN (-4225 2050);
FORCEPROP 2 LAST CDS_LIB logical_power
J 0
(-4425 2000);
DISPLAY INVISIBLE (-4425 2000);
FORCEPROP 1 LAST PATH I22
J 0
(-4375 2025);
DISPLAY 0.872340 (-4375 2025);
PAINT AQUA (-4375 2025);
DISPLAY INVISIBLE (-4375 2025);
FORCEADD Q_CAP..1
(-4425 2450);
FORCEPROP 1 LAST PART_NUMBER CH647KMEA04
J 0
(-4375 2300);
DISPLAY 0.638298 (-4375 2300);
DISPLAY INVISIBLE (-4375 2300);
FORCEPROP 1 LAST VALUE 47UF
J 0
(-4375 2500);
DISPLAY 0.638298 (-4375 2500);
FORCEPROP 1 LAST VOLTAGE 4V
J 0
(-4375 2450);
DISPLAY 0.638298 (-4375 2450);
FORCEPROP 1 LAST TOLERANCE 20%
J 0
(-4375 2400);
DISPLAY 0.638298 (-4375 2400);
FORCEPROP 1 LAST PACK_TYPE C0805
J 0
(-4375 2250);
DISPLAY 0.638298 (-4375 2250);
FORCEPROP 1 LAST MATERIAL X6S
J 0
(-4375 2350);
DISPLAY 0.638298 (-4375 2350);
FORCEPROP 1 LAST $LOCATION C355
J 0
(-4375 2550);
DISPLAY 0.638298 (-4375 2550);
FORCEPROP 1 LASTPIN (-4425 2550) $PN 1
J 0
(-4415 2530);
DISPLAY 0.787234 (-4415 2530);
FORCEPROP 1 LASTPIN (-4425 2350) $PN 2
J 0
(-4415 2330);
DISPLAY 0.787234 (-4415 2330);
FORCEPROP 2 LAST CDS_LIB pure_quanta
J 0
(-4425 2450);
PAINT MONO (-4425 2450);
DISPLAY INVISIBLE (-4425 2450);
FORCEPROP 1 LAST $LOCATION C355
J 0
(-4375 2650);
DISPLAY 1.021277 (-4375 2650);
DISPLAY INVISIBLE (-4375 2650);
FORCEPROP 2 LAST CDS_LOCATION C355
J 0
(-4375 2650);
DISPLAY 1.021277 (-4375 2650);
DISPLAY INVISIBLE (-4375 2650);
FORCEPROP 2 LAST $SEC 1
J 0
(-4375 2650);
DISPLAY 0.680851 (-4375 2650);
PAINT MONO (-4375 2650);
DISPLAY INVISIBLE (-4375 2650);
FORCEPROP 2 LAST CDS_SEC 1
J 0
(-4375 2650);
DISPLAY 1.021277 (-4375 2650);
DISPLAY INVISIBLE (-4375 2650);
FORCEPROP 1 LAST PATH I23
J 0
(-4375 2600);
DISPLAY 0.978723 (-4375 2600);
PAINT WHITE (-4375 2600);
DISPLAY INVISIBLE (-4375 2600);
FORCEADD UNIVERSAL_POWER..1
(-4425 2725);
FORCEPROP 3 LASTPIN (-4425 2675) SIG_NAME PVCCIN_CPU0\g
J 0
(-4415 2685);
DISPLAY 0.659574 (-4415 2685);
PAINT MONO (-4415 2685);
DISPLAY INVISIBLE (-4415 2685);
FORCEPROP 1 LAST HDL_POWER PVCCIN_CPU0
J 1
(-4225 2775);
DISPLAY 0.872340 (-4225 2775);
PAINT GREEN (-4225 2775);
FORCEPROP 2 LAST CDS_LIB logical_power
J 0
(-4425 2725);
DISPLAY INVISIBLE (-4425 2725);
FORCEPROP 1 LAST PATH I24
J 0
(-4375 2750);
DISPLAY 0.872340 (-4375 2750);
PAINT AQUA (-4375 2750);
DISPLAY INVISIBLE (-4375 2750);
FORCEADD Q_CAP..1
(-3975 1725);
FORCEPROP 1 LAST PART_NUMBER CH647KMEA04
J 0
(-3925 1575);
DISPLAY 0.638298 (-3925 1575);
DISPLAY INVISIBLE (-3925 1575);
FORCEPROP 1 LAST VALUE 47UF
J 0
(-3925 1775);
DISPLAY 0.638298 (-3925 1775);
FORCEPROP 1 LAST VOLTAGE 4V
J 0
(-3925 1725);
DISPLAY 0.638298 (-3925 1725);
FORCEPROP 1 LAST TOLERANCE 20%
J 0
(-3925 1675);
DISPLAY 0.638298 (-3925 1675);
FORCEPROP 1 LAST PACK_TYPE C0805
J 0
(-3925 1525);
DISPLAY 0.638298 (-3925 1525);
FORCEPROP 1 LAST MATERIAL X6S
J 0
(-3925 1625);
DISPLAY 0.638298 (-3925 1625);
FORCEPROP 1 LAST $LOCATION C359
J 0
(-3925 1825);
DISPLAY 0.638298 (-3925 1825);
FORCEPROP 1 LASTPIN (-3975 1825) $PN 1
J 0
(-3965 1805);
DISPLAY 0.787234 (-3965 1805);
FORCEPROP 1 LASTPIN (-3975 1625) $PN 2
J 0
(-3965 1605);
DISPLAY 0.787234 (-3965 1605);
FORCEPROP 2 LAST CDS_LIB pure_quanta
J 0
(-3975 1725);
PAINT MONO (-3975 1725);
DISPLAY INVISIBLE (-3975 1725);
FORCEPROP 1 LAST $LOCATION C359
J 0
(-3925 1925);
DISPLAY 1.021277 (-3925 1925);
DISPLAY INVISIBLE (-3925 1925);
FORCEPROP 2 LAST CDS_LOCATION C359
J 0
(-3925 1925);
DISPLAY 1.021277 (-3925 1925);
DISPLAY INVISIBLE (-3925 1925);
FORCEPROP 2 LAST $SEC 1
J 0
(-3925 1925);
DISPLAY 0.680851 (-3925 1925);
PAINT MONO (-3925 1925);
DISPLAY INVISIBLE (-3925 1925);
FORCEPROP 2 LAST CDS_SEC 1
J 0
(-3925 1925);
DISPLAY 1.021277 (-3925 1925);
DISPLAY INVISIBLE (-3925 1925);
FORCEPROP 1 LAST PATH I25
J 0
(-3925 1875);
DISPLAY 0.978723 (-3925 1875);
PAINT WHITE (-3925 1875);
DISPLAY INVISIBLE (-3925 1875);
FORCEADD Q_CAP..1
(-3525 1725);
FORCEPROP 1 LAST PART_NUMBER CH647KMEA04
J 0
(-3475 1575);
DISPLAY 0.638298 (-3475 1575);
DISPLAY INVISIBLE (-3475 1575);
FORCEPROP 1 LAST VALUE 47UF
J 0
(-3475 1775);
DISPLAY 0.638298 (-3475 1775);
FORCEPROP 1 LAST VOLTAGE 4V
J 0
(-3475 1725);
DISPLAY 0.638298 (-3475 1725);
FORCEPROP 1 LAST TOLERANCE 20%
J 0
(-3475 1675);
DISPLAY 0.638298 (-3475 1675);
FORCEPROP 1 LAST PACK_TYPE C0805
J 0
(-3475 1525);
DISPLAY 0.638298 (-3475 1525);
FORCEPROP 1 LAST MATERIAL X6S
J 0
(-3475 1625);
DISPLAY 0.638298 (-3475 1625);
FORCEPROP 1 LAST $LOCATION C362
J 0
(-3475 1825);
DISPLAY 0.638298 (-3475 1825);
FORCEPROP 1 LASTPIN (-3525 1825) $PN 1
J 0
(-3515 1805);
DISPLAY 0.787234 (-3515 1805);
FORCEPROP 1 LASTPIN (-3525 1625) $PN 2
J 0
(-3515 1605);
DISPLAY 0.787234 (-3515 1605);
FORCEPROP 2 LAST CDS_LIB pure_quanta
J 0
(-3525 1725);
PAINT MONO (-3525 1725);
DISPLAY INVISIBLE (-3525 1725);
FORCEPROP 1 LAST $LOCATION C362
J 0
(-3475 1925);
DISPLAY 1.021277 (-3475 1925);
DISPLAY INVISIBLE (-3475 1925);
FORCEPROP 2 LAST CDS_LOCATION C362
J 0
(-3475 1925);
DISPLAY 1.021277 (-3475 1925);
DISPLAY INVISIBLE (-3475 1925);
FORCEPROP 2 LAST $SEC 1
J 0
(-3475 1925);
DISPLAY 0.680851 (-3475 1925);
PAINT MONO (-3475 1925);
DISPLAY INVISIBLE (-3475 1925);
FORCEPROP 2 LAST CDS_SEC 1
J 0
(-3475 1925);
DISPLAY 1.021277 (-3475 1925);
DISPLAY INVISIBLE (-3475 1925);
FORCEPROP 1 LAST PATH I26
J 0
(-3475 1875);
DISPLAY 0.978723 (-3475 1875);
PAINT WHITE (-3475 1875);
DISPLAY INVISIBLE (-3475 1875);
FORCEADD Q_CAP..1
(-3975 2450);
FORCEPROP 1 LAST PART_NUMBER CH647KMEA04
J 0
(-3925 2300);
DISPLAY 0.638298 (-3925 2300);
DISPLAY INVISIBLE (-3925 2300);
FORCEPROP 1 LAST VALUE 47UF
J 0
(-3925 2500);
DISPLAY 0.638298 (-3925 2500);
FORCEPROP 1 LAST VOLTAGE 4V
J 0
(-3925 2450);
DISPLAY 0.638298 (-3925 2450);
FORCEPROP 1 LAST TOLERANCE 20%
J 0
(-3925 2400);
DISPLAY 0.638298 (-3925 2400);
FORCEPROP 1 LAST PACK_TYPE C0805
J 0
(-3925 2250);
DISPLAY 0.638298 (-3925 2250);
FORCEPROP 1 LAST MATERIAL X6S
J 0
(-3925 2350);
DISPLAY 0.638298 (-3925 2350);
FORCEPROP 1 LAST $LOCATION C358
J 0
(-3925 2550);
DISPLAY 0.638298 (-3925 2550);
FORCEPROP 1 LASTPIN (-3975 2550) $PN 1
J 0
(-3965 2530);
DISPLAY 0.787234 (-3965 2530);
FORCEPROP 1 LASTPIN (-3975 2350) $PN 2
J 0
(-3965 2330);
DISPLAY 0.787234 (-3965 2330);
FORCEPROP 2 LAST CDS_LIB pure_quanta
J 0
(-3975 2450);
PAINT MONO (-3975 2450);
DISPLAY INVISIBLE (-3975 2450);
FORCEPROP 1 LAST $LOCATION C358
J 0
(-3925 2650);
DISPLAY 1.021277 (-3925 2650);
DISPLAY INVISIBLE (-3925 2650);
FORCEPROP 2 LAST CDS_LOCATION C358
J 0
(-3925 2650);
DISPLAY 1.021277 (-3925 2650);
DISPLAY INVISIBLE (-3925 2650);
FORCEPROP 2 LAST $SEC 1
J 0
(-3925 2650);
DISPLAY 0.680851 (-3925 2650);
PAINT MONO (-3925 2650);
DISPLAY INVISIBLE (-3925 2650);
FORCEPROP 2 LAST CDS_SEC 1
J 0
(-3925 2650);
DISPLAY 1.021277 (-3925 2650);
DISPLAY INVISIBLE (-3925 2650);
FORCEPROP 1 LAST PATH I27
J 0
(-3925 2600);
DISPLAY 0.978723 (-3925 2600);
PAINT WHITE (-3925 2600);
DISPLAY INVISIBLE (-3925 2600);
FORCEADD Q_CAP..1
(-3525 2450);
FORCEPROP 1 LAST PART_NUMBER CH647KMEA04
J 0
(-3475 2300);
DISPLAY 0.638298 (-3475 2300);
DISPLAY INVISIBLE (-3475 2300);
FORCEPROP 1 LAST VALUE 47UF
J 0
(-3475 2500);
DISPLAY 0.638298 (-3475 2500);
FORCEPROP 1 LAST VOLTAGE 4V
J 0
(-3475 2450);
DISPLAY 0.638298 (-3475 2450);
FORCEPROP 1 LAST TOLERANCE 20%
J 0
(-3475 2400);
DISPLAY 0.638298 (-3475 2400);
FORCEPROP 1 LAST PACK_TYPE C0805
J 0
(-3475 2250);
DISPLAY 0.638298 (-3475 2250);
FORCEPROP 1 LAST MATERIAL X6S
J 0
(-3475 2350);
DISPLAY 0.638298 (-3475 2350);
FORCEPROP 1 LAST $LOCATION C361
J 0
(-3475 2550);
DISPLAY 0.638298 (-3475 2550);
FORCEPROP 1 LASTPIN (-3525 2550) $PN 1
J 0
(-3515 2530);
DISPLAY 0.787234 (-3515 2530);
FORCEPROP 1 LASTPIN (-3525 2350) $PN 2
J 0
(-3515 2330);
DISPLAY 0.787234 (-3515 2330);
FORCEPROP 2 LAST CDS_LIB pure_quanta
J 0
(-3525 2450);
PAINT MONO (-3525 2450);
DISPLAY INVISIBLE (-3525 2450);
FORCEPROP 1 LAST $LOCATION C361
J 0
(-3475 2650);
DISPLAY 1.021277 (-3475 2650);
DISPLAY INVISIBLE (-3475 2650);
FORCEPROP 2 LAST CDS_LOCATION C361
J 0
(-3475 2650);
DISPLAY 1.021277 (-3475 2650);
DISPLAY INVISIBLE (-3475 2650);
FORCEPROP 2 LAST $SEC 1
J 0
(-3475 2650);
DISPLAY 0.680851 (-3475 2650);
PAINT MONO (-3475 2650);
DISPLAY INVISIBLE (-3475 2650);
FORCEPROP 2 LAST CDS_SEC 1
J 0
(-3475 2650);
DISPLAY 1.021277 (-3475 2650);
DISPLAY INVISIBLE (-3475 2650);
FORCEPROP 1 LAST PATH I28
J 0
(-3475 2600);
DISPLAY 0.978723 (-3475 2600);
PAINT WHITE (-3475 2600);
DISPLAY INVISIBLE (-3475 2600);
FORCEADD Q_CAP..1
(-3075 -1225);
FORCEPROP 1 LAST PART_NUMBER CH622KMEB01
J 0
(-3025 -1375);
DISPLAY 0.638298 (-3025 -1375);
DISPLAY INVISIBLE (-3025 -1375);
FORCEPROP 1 LAST TOLERANCE 20%
J 0
(-3025 -1275);
DISPLAY 0.638298 (-3025 -1275);
FORCEPROP 1 LAST MATERIAL X6S
J 0
(-3025 -1325);
DISPLAY 0.638298 (-3025 -1325);
FORCEPROP 1 LAST VOLTAGE 4V
J 0
(-3025 -1225);
DISPLAY 0.638298 (-3025 -1225);
FORCEPROP 1 LAST VALUE 22UF
J 0
(-3025 -1175);
DISPLAY 0.638298 (-3025 -1175);
FORCEPROP 1 LAST PACK_TYPE C0402
J 0
(-3025 -1425);
DISPLAY 0.638298 (-3025 -1425);
FORCEPROP 1 LAST $LOCATION C534
J 0
(-3025 -1125);
DISPLAY 0.978723 (-3025 -1125);
FORCEPROP 1 LASTPIN (-3075 -1125) $PN 1
J 0
(-3065 -1145);
DISPLAY 0.787234 (-3065 -1145);
FORCEPROP 1 LASTPIN (-3075 -1325) $PN 2
J 0
(-3065 -1345);
DISPLAY 0.787234 (-3065 -1345);
FORCEPROP 2 LAST CDS_LIB pure_quanta
J 0
(-3075 -1225);
PAINT MONO (-3075 -1225);
DISPLAY INVISIBLE (-3075 -1225);
FORCEPROP 2 LAST CDS_LOCATION C534
J 0
(-3025 -1025);
DISPLAY 1.021277 (-3025 -1025);
DISPLAY INVISIBLE (-3025 -1025);
FORCEPROP 2 LAST $SEC 1
J 0
(-3025 -1025);
DISPLAY 0.680851 (-3025 -1025);
PAINT MONO (-3025 -1025);
DISPLAY INVISIBLE (-3025 -1025);
FORCEPROP 2 LAST CDS_SEC 1
J 0
(-3025 -1025);
DISPLAY 1.021277 (-3025 -1025);
DISPLAY INVISIBLE (-3025 -1025);
FORCEPROP 1 LAST PATH I29
J 0
(-3025 -1075);
DISPLAY 0.978723 (-3025 -1075);
PAINT WHITE (-3025 -1075);
DISPLAY INVISIBLE (-3025 -1075);
FORCEADD Q_CAP..1
(-3975 -2225);
FORCEPROP 1 LAST PART_NUMBER CH647KMEA04
J 0
(-3925 -2375);
DISPLAY 0.638298 (-3925 -2375);
DISPLAY INVISIBLE (-3925 -2375);
FORCEPROP 1 LAST VOLTAGE 4V
J 0
(-3925 -2225);
DISPLAY 0.638298 (-3925 -2225);
FORCEPROP 1 LAST TOLERANCE 20%
J 0
(-3925 -2275);
DISPLAY 0.638298 (-3925 -2275);
FORCEPROP 1 LAST PACK_TYPE C0805
J 0
(-3925 -2425);
DISPLAY 0.638298 (-3925 -2425);
FORCEPROP 1 LAST VALUE 47UF
J 0
(-3925 -2175);
DISPLAY 0.638298 (-3925 -2175);
FORCEPROP 1 LAST MATERIAL X6S
J 0
(-3925 -2325);
DISPLAY 0.638298 (-3925 -2325);
FORCEPROP 1 LAST $LOCATION C497
J 0
(-3925 -2125);
DISPLAY 0.978723 (-3925 -2125);
FORCEPROP 1 LASTPIN (-3975 -2125) $PN 1
J 0
(-3965 -2145);
DISPLAY 0.787234 (-3965 -2145);
FORCEPROP 1 LASTPIN (-3975 -2325) $PN 2
J 0
(-3965 -2345);
DISPLAY 0.787234 (-3965 -2345);
FORCEPROP 2 LAST CDS_LIB pure_quanta
J 0
(-3975 -2225);
PAINT MONO (-3975 -2225);
DISPLAY INVISIBLE (-3975 -2225);
FORCEPROP 2 LAST CDS_LOCATION C497
J 0
(-3925 -2025);
DISPLAY 1.021277 (-3925 -2025);
DISPLAY INVISIBLE (-3925 -2025);
FORCEPROP 2 LAST $SEC 1
J 0
(-3925 -2025);
DISPLAY 0.680851 (-3925 -2025);
PAINT MONO (-3925 -2025);
DISPLAY INVISIBLE (-3925 -2025);
FORCEPROP 2 LAST CDS_SEC 1
J 0
(-3925 -2025);
DISPLAY 1.021277 (-3925 -2025);
DISPLAY INVISIBLE (-3925 -2025);
FORCEPROP 1 LAST PATH I3
J 0
(-3925 -2075);
DISPLAY 0.978723 (-3925 -2075);
PAINT WHITE (-3925 -2075);
DISPLAY INVISIBLE (-3925 -2075);
FORCEADD UNIVERSAL_GND..1
(-3075 400);
FORCEPROP 3 LASTPIN (-3075 450) SIG_NAME GND\g
J 0
(-3065 460);
DISPLAY 0.659574 (-3065 460);
PAINT MONO (-3065 460);
DISPLAY INVISIBLE (-3065 460);
FORCEPROP 2 LAST CDS_LIB logical_power
J 0
(-3075 400);
PAINT MONO (-3075 400);
DISPLAY INVISIBLE (-3075 400);
FORCEPROP 1 LAST HDL_POWER GND
J 1
(-3050 325);
DISPLAY 0.872340 (-3050 325);
PAINT GREEN (-3050 325);
DISPLAY INVISIBLE (-3050 325);
FORCEPROP 1 LAST PATH I30
J 0
(-3000 400);
DISPLAY 0.872340 (-3000 400);
PAINT AQUA (-3000 400);
DISPLAY INVISIBLE (-3000 400);
FORCEADD Q_CAP..1
(-3075 725);
FORCEPROP 1 LAST PART_NUMBER CH647KMEA04
J 0
(-3025 575);
DISPLAY 0.638298 (-3025 575);
DISPLAY INVISIBLE (-3025 575);
FORCEPROP 1 LAST TOLERANCE 20%
J 0
(-3025 675);
DISPLAY 0.638298 (-3025 675);
FORCEPROP 1 LAST VOLTAGE 4V
J 0
(-3025 725);
DISPLAY 0.638298 (-3025 725);
FORCEPROP 1 LAST VALUE 47UF
J 0
(-3025 775);
DISPLAY 0.638298 (-3025 775);
FORCEPROP 1 LAST PACK_TYPE C0805
J 0
(-3025 525);
DISPLAY 0.638298 (-3025 525);
FORCEPROP 1 LAST MATERIAL X6S
J 0
(-3025 625);
DISPLAY 0.638298 (-3025 625);
FORCEPROP 1 LAST $LOCATION C518
J 0
(-3025 825);
DISPLAY 0.978723 (-3025 825);
FORCEPROP 1 LASTPIN (-3075 825) $PN 1
J 0
(-3065 805);
DISPLAY 0.787234 (-3065 805);
PAINT MONO (-3065 805);
FORCEPROP 1 LASTPIN (-3075 625) $PN 2
J 0
(-3065 605);
DISPLAY 0.787234 (-3065 605);
PAINT MONO (-3065 605);
FORCEPROP 2 LAST CDS_LIB pure_quanta
J 0
(-3075 725);
DISPLAY INVISIBLE (-3075 725);
FORCEPROP 2 LAST CDS_LOCATION C518
J 0
(-3025 925);
DISPLAY 1.021277 (-3025 925);
DISPLAY INVISIBLE (-3025 925);
FORCEPROP 0 LAST $SEC 1
J 0
(-3025 875);
DISPLAY 0.680851 (-3025 875);
PAINT MONO (-3025 875);
DISPLAY INVISIBLE (-3025 875);
FORCEPROP 2 LAST CDS_SEC 1
J 0
(-3025 925);
DISPLAY 1.021277 (-3025 925);
DISPLAY INVISIBLE (-3025 925);
FORCEPROP 1 LAST PATH I31
J 0
(-3025 875);
DISPLAY 0.978723 (-3025 875);
PAINT WHITE (-3025 875);
DISPLAY INVISIBLE (-3025 875);
FORCEADD Q_CAP..1
(-3075 1725);
FORCEPROP 1 LAST PART_NUMBER CH647KMEA04
J 0
(-3025 1575);
DISPLAY 0.638298 (-3025 1575);
DISPLAY INVISIBLE (-3025 1575);
FORCEPROP 1 LAST VALUE 47UF
J 0
(-3025 1775);
DISPLAY 0.638298 (-3025 1775);
FORCEPROP 1 LAST VOLTAGE 4V
J 0
(-3025 1725);
DISPLAY 0.638298 (-3025 1725);
FORCEPROP 1 LAST TOLERANCE 20%
J 0
(-3025 1675);
DISPLAY 0.638298 (-3025 1675);
FORCEPROP 1 LAST PACK_TYPE C0805
J 0
(-3025 1525);
DISPLAY 0.638298 (-3025 1525);
FORCEPROP 1 LAST MATERIAL X6S
J 0
(-3025 1625);
DISPLAY 0.638298 (-3025 1625);
FORCEPROP 1 LAST $LOCATION C365
J 0
(-3025 1825);
DISPLAY 0.638298 (-3025 1825);
FORCEPROP 1 LASTPIN (-3075 1825) $PN 1
J 0
(-3065 1805);
DISPLAY 0.787234 (-3065 1805);
FORCEPROP 1 LASTPIN (-3075 1625) $PN 2
J 0
(-3065 1605);
DISPLAY 0.787234 (-3065 1605);
FORCEPROP 2 LAST CDS_LIB pure_quanta
J 0
(-3075 1725);
PAINT MONO (-3075 1725);
DISPLAY INVISIBLE (-3075 1725);
FORCEPROP 1 LAST $LOCATION C365
J 0
(-3025 1925);
DISPLAY 1.021277 (-3025 1925);
DISPLAY INVISIBLE (-3025 1925);
FORCEPROP 2 LAST CDS_LOCATION C365
J 0
(-3025 1925);
DISPLAY 1.021277 (-3025 1925);
DISPLAY INVISIBLE (-3025 1925);
FORCEPROP 2 LAST $SEC 1
J 0
(-3025 1925);
DISPLAY 0.680851 (-3025 1925);
PAINT MONO (-3025 1925);
DISPLAY INVISIBLE (-3025 1925);
FORCEPROP 2 LAST CDS_SEC 1
J 0
(-3025 1925);
DISPLAY 1.021277 (-3025 1925);
DISPLAY INVISIBLE (-3025 1925);
FORCEPROP 1 LAST PATH I32
J 0
(-3025 1875);
DISPLAY 0.978723 (-3025 1875);
PAINT WHITE (-3025 1875);
DISPLAY INVISIBLE (-3025 1875);
FORCEADD Q_CAP..1
(-2625 1725);
FORCEPROP 1 LAST PART_NUMBER CH647KMEA04
J 0
(-2575 1575);
DISPLAY 0.638298 (-2575 1575);
DISPLAY INVISIBLE (-2575 1575);
FORCEPROP 1 LAST VALUE 47UF
J 0
(-2575 1775);
DISPLAY 0.638298 (-2575 1775);
FORCEPROP 1 LAST VOLTAGE 4V
J 0
(-2575 1725);
DISPLAY 0.638298 (-2575 1725);
FORCEPROP 1 LAST TOLERANCE 20%
J 0
(-2575 1675);
DISPLAY 0.638298 (-2575 1675);
FORCEPROP 1 LAST PACK_TYPE C0805
J 0
(-2575 1525);
DISPLAY 0.638298 (-2575 1525);
FORCEPROP 1 LAST MATERIAL X6S
J 0
(-2575 1625);
DISPLAY 0.638298 (-2575 1625);
FORCEPROP 1 LAST $LOCATION C368
J 0
(-2575 1825);
DISPLAY 0.638298 (-2575 1825);
FORCEPROP 1 LASTPIN (-2625 1825) $PN 1
J 0
(-2615 1805);
DISPLAY 0.787234 (-2615 1805);
FORCEPROP 1 LASTPIN (-2625 1625) $PN 2
J 0
(-2615 1605);
DISPLAY 0.787234 (-2615 1605);
FORCEPROP 2 LAST CDS_LIB pure_quanta
J 0
(-2625 1725);
PAINT MONO (-2625 1725);
DISPLAY INVISIBLE (-2625 1725);
FORCEPROP 1 LAST $LOCATION C368
J 0
(-2575 1925);
DISPLAY 1.021277 (-2575 1925);
DISPLAY INVISIBLE (-2575 1925);
FORCEPROP 2 LAST CDS_LOCATION C368
J 0
(-2575 1925);
DISPLAY 1.021277 (-2575 1925);
DISPLAY INVISIBLE (-2575 1925);
FORCEPROP 2 LAST $SEC 1
J 0
(-2575 1925);
DISPLAY 0.680851 (-2575 1925);
PAINT MONO (-2575 1925);
DISPLAY INVISIBLE (-2575 1925);
FORCEPROP 2 LAST CDS_SEC 1
J 0
(-2575 1925);
DISPLAY 1.021277 (-2575 1925);
DISPLAY INVISIBLE (-2575 1925);
FORCEPROP 1 LAST PATH I33
J 0
(-2575 1875);
DISPLAY 0.978723 (-2575 1875);
PAINT WHITE (-2575 1875);
DISPLAY INVISIBLE (-2575 1875);
FORCEADD Q_CAP..1
(-3075 2450);
FORCEPROP 1 LAST PART_NUMBER CH647KMEA04
J 0
(-3025 2300);
DISPLAY 0.638298 (-3025 2300);
DISPLAY INVISIBLE (-3025 2300);
FORCEPROP 1 LAST VALUE 47UF
J 0
(-3025 2500);
DISPLAY 0.638298 (-3025 2500);
FORCEPROP 1 LAST VOLTAGE 4V
J 0
(-3025 2450);
DISPLAY 0.638298 (-3025 2450);
FORCEPROP 1 LAST TOLERANCE 20%
J 0
(-3025 2400);
DISPLAY 0.638298 (-3025 2400);
FORCEPROP 1 LAST PACK_TYPE C0805
J 0
(-3025 2250);
DISPLAY 0.638298 (-3025 2250);
FORCEPROP 1 LAST MATERIAL X6S
J 0
(-3025 2350);
DISPLAY 0.638298 (-3025 2350);
FORCEPROP 1 LAST $LOCATION C364
J 0
(-3025 2550);
DISPLAY 0.638298 (-3025 2550);
FORCEPROP 1 LASTPIN (-3075 2550) $PN 1
J 0
(-3065 2530);
DISPLAY 0.787234 (-3065 2530);
FORCEPROP 1 LASTPIN (-3075 2350) $PN 2
J 0
(-3065 2330);
DISPLAY 0.787234 (-3065 2330);
FORCEPROP 2 LAST CDS_LIB pure_quanta
J 0
(-3075 2450);
PAINT MONO (-3075 2450);
DISPLAY INVISIBLE (-3075 2450);
FORCEPROP 1 LAST $LOCATION C364
J 0
(-3025 2650);
DISPLAY 1.021277 (-3025 2650);
DISPLAY INVISIBLE (-3025 2650);
FORCEPROP 2 LAST CDS_LOCATION C364
J 0
(-3025 2650);
DISPLAY 1.021277 (-3025 2650);
DISPLAY INVISIBLE (-3025 2650);
FORCEPROP 2 LAST $SEC 1
J 0
(-3025 2650);
DISPLAY 0.680851 (-3025 2650);
PAINT MONO (-3025 2650);
DISPLAY INVISIBLE (-3025 2650);
FORCEPROP 2 LAST CDS_SEC 1
J 0
(-3025 2650);
DISPLAY 1.021277 (-3025 2650);
DISPLAY INVISIBLE (-3025 2650);
FORCEPROP 1 LAST PATH I34
J 0
(-3025 2600);
DISPLAY 0.978723 (-3025 2600);
PAINT WHITE (-3025 2600);
DISPLAY INVISIBLE (-3025 2600);
FORCEADD Q_CAP..1
(-2625 2450);
FORCEPROP 1 LAST PART_NUMBER CH647KMEA04
J 0
(-2575 2300);
DISPLAY 0.638298 (-2575 2300);
DISPLAY INVISIBLE (-2575 2300);
FORCEPROP 1 LAST VALUE 47UF
J 0
(-2575 2500);
DISPLAY 0.638298 (-2575 2500);
FORCEPROP 1 LAST VOLTAGE 4V
J 0
(-2575 2450);
DISPLAY 0.638298 (-2575 2450);
FORCEPROP 1 LAST TOLERANCE 20%
J 0
(-2575 2400);
DISPLAY 0.638298 (-2575 2400);
FORCEPROP 1 LAST PACK_TYPE C0805
J 0
(-2575 2250);
DISPLAY 0.638298 (-2575 2250);
FORCEPROP 1 LAST MATERIAL X6S
J 0
(-2575 2350);
DISPLAY 0.638298 (-2575 2350);
FORCEPROP 1 LAST $LOCATION C367
J 0
(-2575 2550);
DISPLAY 0.638298 (-2575 2550);
FORCEPROP 1 LASTPIN (-2625 2550) $PN 1
J 0
(-2615 2530);
DISPLAY 0.787234 (-2615 2530);
FORCEPROP 1 LASTPIN (-2625 2350) $PN 2
J 0
(-2615 2330);
DISPLAY 0.787234 (-2615 2330);
FORCEPROP 2 LAST CDS_LIB pure_quanta
J 0
(-2625 2450);
PAINT MONO (-2625 2450);
DISPLAY INVISIBLE (-2625 2450);
FORCEPROP 1 LAST $LOCATION C367
J 0
(-2575 2650);
DISPLAY 1.021277 (-2575 2650);
DISPLAY INVISIBLE (-2575 2650);
FORCEPROP 2 LAST CDS_LOCATION C367
J 0
(-2575 2650);
DISPLAY 1.021277 (-2575 2650);
DISPLAY INVISIBLE (-2575 2650);
FORCEPROP 2 LAST $SEC 1
J 0
(-2575 2650);
DISPLAY 0.680851 (-2575 2650);
PAINT MONO (-2575 2650);
DISPLAY INVISIBLE (-2575 2650);
FORCEPROP 2 LAST CDS_SEC 1
J 0
(-2575 2650);
DISPLAY 1.021277 (-2575 2650);
DISPLAY INVISIBLE (-2575 2650);
FORCEPROP 1 LAST PATH I35
J 0
(-2575 2600);
DISPLAY 0.978723 (-2575 2600);
PAINT WHITE (-2575 2600);
DISPLAY INVISIBLE (-2575 2600);
FORCEADD Q_CAP..1
(-2175 1725);
FORCEPROP 1 LAST PART_NUMBER CH647KMEA04
J 0
(-2125 1575);
DISPLAY 0.638298 (-2125 1575);
DISPLAY INVISIBLE (-2125 1575);
FORCEPROP 1 LAST VALUE 47UF
J 0
(-2125 1775);
DISPLAY 0.638298 (-2125 1775);
FORCEPROP 1 LAST VOLTAGE 4V
J 0
(-2125 1725);
DISPLAY 0.638298 (-2125 1725);
FORCEPROP 1 LAST TOLERANCE 20%
J 0
(-2125 1675);
DISPLAY 0.638298 (-2125 1675);
FORCEPROP 1 LAST PACK_TYPE C0805
J 0
(-2125 1525);
DISPLAY 0.638298 (-2125 1525);
FORCEPROP 1 LAST MATERIAL X6S
J 0
(-2125 1625);
DISPLAY 0.638298 (-2125 1625);
FORCEPROP 1 LAST $LOCATION C371
J 0
(-2125 1825);
DISPLAY 0.638298 (-2125 1825);
FORCEPROP 1 LASTPIN (-2175 1825) $PN 1
J 0
(-2165 1805);
DISPLAY 0.787234 (-2165 1805);
FORCEPROP 1 LASTPIN (-2175 1625) $PN 2
J 0
(-2165 1605);
DISPLAY 0.787234 (-2165 1605);
FORCEPROP 2 LAST CDS_LIB pure_quanta
J 0
(-2175 1725);
PAINT MONO (-2175 1725);
DISPLAY INVISIBLE (-2175 1725);
FORCEPROP 1 LAST $LOCATION C371
J 0
(-2125 1925);
DISPLAY 1.021277 (-2125 1925);
DISPLAY INVISIBLE (-2125 1925);
FORCEPROP 2 LAST CDS_LOCATION C371
J 0
(-2125 1925);
DISPLAY 1.021277 (-2125 1925);
DISPLAY INVISIBLE (-2125 1925);
FORCEPROP 2 LAST $SEC 1
J 0
(-2125 1925);
DISPLAY 0.680851 (-2125 1925);
PAINT MONO (-2125 1925);
DISPLAY INVISIBLE (-2125 1925);
FORCEPROP 2 LAST CDS_SEC 1
J 0
(-2125 1925);
DISPLAY 1.021277 (-2125 1925);
DISPLAY INVISIBLE (-2125 1925);
FORCEPROP 1 LAST PATH I36
J 0
(-2125 1875);
DISPLAY 0.978723 (-2125 1875);
PAINT WHITE (-2125 1875);
DISPLAY INVISIBLE (-2125 1875);
FORCEADD Q_CAP..1
(-1725 1725);
FORCEPROP 1 LAST PART_NUMBER CH647KMEA04
J 0
(-1675 1575);
DISPLAY 0.638298 (-1675 1575);
DISPLAY INVISIBLE (-1675 1575);
FORCEPROP 1 LAST VALUE 47UF
J 0
(-1675 1775);
DISPLAY 0.638298 (-1675 1775);
FORCEPROP 1 LAST VOLTAGE 4V
J 0
(-1675 1725);
DISPLAY 0.638298 (-1675 1725);
FORCEPROP 1 LAST TOLERANCE 20%
J 0
(-1675 1675);
DISPLAY 0.638298 (-1675 1675);
FORCEPROP 1 LAST PACK_TYPE C0805
J 0
(-1675 1525);
DISPLAY 0.638298 (-1675 1525);
FORCEPROP 1 LAST MATERIAL X6S
J 0
(-1675 1625);
DISPLAY 0.638298 (-1675 1625);
FORCEPROP 1 LAST $LOCATION C397
J 0
(-1675 1825);
DISPLAY 0.638298 (-1675 1825);
FORCEPROP 1 LASTPIN (-1725 1825) $PN 1
J 0
(-1715 1805);
DISPLAY 0.787234 (-1715 1805);
FORCEPROP 1 LASTPIN (-1725 1625) $PN 2
J 0
(-1715 1605);
DISPLAY 0.787234 (-1715 1605);
FORCEPROP 2 LAST CDS_LIB pure_quanta
J 0
(-1725 1725);
PAINT MONO (-1725 1725);
DISPLAY INVISIBLE (-1725 1725);
FORCEPROP 0 LAST CDS_LOCATION C397
J 0
(-1675 1875);
DISPLAY 1.021277 (-1675 1875);
DISPLAY INVISIBLE (-1675 1875);
FORCEPROP 2 LAST $SEC 1
J 0
(-1675 1925);
DISPLAY 0.680851 (-1675 1925);
PAINT MONO (-1675 1925);
DISPLAY INVISIBLE (-1675 1925);
FORCEPROP 2 LAST CDS_SEC 1
J 0
(-1675 1925);
DISPLAY 1.021277 (-1675 1925);
DISPLAY INVISIBLE (-1675 1925);
FORCEPROP 1 LAST PATH I37
J 0
(-1675 1875);
DISPLAY 0.978723 (-1675 1875);
PAINT WHITE (-1675 1875);
DISPLAY INVISIBLE (-1675 1875);
FORCEADD Q_CAP..1
(-1275 1725);
FORCEPROP 1 LAST PART_NUMBER CH647KMEA04
J 0
(-1225 1575);
DISPLAY 0.638298 (-1225 1575);
DISPLAY INVISIBLE (-1225 1575);
FORCEPROP 1 LAST PACK_TYPE C0805
J 0
(-1225 1525);
DISPLAY 0.638298 (-1225 1525);
FORCEPROP 1 LAST VALUE 47UF
J 0
(-1225 1775);
DISPLAY 0.638298 (-1225 1775);
FORCEPROP 1 LAST VOLTAGE 4V
J 0
(-1225 1725);
DISPLAY 0.638298 (-1225 1725);
FORCEPROP 1 LAST TOLERANCE 20%
J 0
(-1225 1675);
DISPLAY 0.638298 (-1225 1675);
FORCEPROP 1 LAST MATERIAL X6S
J 0
(-1225 1625);
DISPLAY 0.638298 (-1225 1625);
FORCEPROP 1 LAST $LOCATION C357
J 0
(-1225 1825);
DISPLAY 0.638298 (-1225 1825);
FORCEPROP 1 LASTPIN (-1275 1825) $PN 1
J 0
(-1265 1805);
DISPLAY 0.787234 (-1265 1805);
FORCEPROP 1 LASTPIN (-1275 1625) $PN 2
J 0
(-1265 1605);
DISPLAY 0.787234 (-1265 1605);
FORCEPROP 2 LAST CDS_LIB pure_quanta
J 0
(-1275 1725);
PAINT MONO (-1275 1725);
DISPLAY INVISIBLE (-1275 1725);
FORCEPROP 0 LAST CDS_LOCATION C357
J 0
(-1225 1875);
DISPLAY 1.021277 (-1225 1875);
DISPLAY INVISIBLE (-1225 1875);
FORCEPROP 2 LAST $SEC 1
J 0
(-1225 1925);
DISPLAY 0.680851 (-1225 1925);
PAINT MONO (-1225 1925);
DISPLAY INVISIBLE (-1225 1925);
FORCEPROP 2 LAST CDS_SEC 1
J 0
(-1225 1925);
DISPLAY 1.021277 (-1225 1925);
DISPLAY INVISIBLE (-1225 1925);
FORCEPROP 1 LAST PATH I38
J 0
(-1225 1875);
DISPLAY 0.978723 (-1225 1875);
PAINT WHITE (-1225 1875);
DISPLAY INVISIBLE (-1225 1875);
FORCEADD Q_CAP..1
(-2175 2450);
FORCEPROP 1 LAST PART_NUMBER CH647KMEA04
J 0
(-2125 2300);
DISPLAY 0.638298 (-2125 2300);
DISPLAY INVISIBLE (-2125 2300);
FORCEPROP 1 LAST VALUE 47UF
J 0
(-2125 2500);
DISPLAY 0.638298 (-2125 2500);
FORCEPROP 1 LAST VOLTAGE 4V
J 0
(-2125 2450);
DISPLAY 0.638298 (-2125 2450);
FORCEPROP 1 LAST TOLERANCE 20%
J 0
(-2125 2400);
DISPLAY 0.638298 (-2125 2400);
FORCEPROP 1 LAST PACK_TYPE C0805
J 0
(-2125 2250);
DISPLAY 0.638298 (-2125 2250);
FORCEPROP 1 LAST MATERIAL X6S
J 0
(-2125 2350);
DISPLAY 0.638298 (-2125 2350);
FORCEPROP 1 LAST $LOCATION C370
J 0
(-2125 2550);
DISPLAY 0.638298 (-2125 2550);
FORCEPROP 1 LASTPIN (-2175 2550) $PN 1
J 0
(-2165 2530);
DISPLAY 0.787234 (-2165 2530);
FORCEPROP 1 LASTPIN (-2175 2350) $PN 2
J 0
(-2165 2330);
DISPLAY 0.787234 (-2165 2330);
FORCEPROP 2 LAST CDS_LIB pure_quanta
J 0
(-2175 2450);
PAINT MONO (-2175 2450);
DISPLAY INVISIBLE (-2175 2450);
FORCEPROP 1 LAST $LOCATION C370
J 0
(-2125 2650);
DISPLAY 1.021277 (-2125 2650);
DISPLAY INVISIBLE (-2125 2650);
FORCEPROP 2 LAST CDS_LOCATION C370
J 0
(-2125 2650);
DISPLAY 1.021277 (-2125 2650);
DISPLAY INVISIBLE (-2125 2650);
FORCEPROP 2 LAST $SEC 1
J 0
(-2125 2650);
DISPLAY 0.680851 (-2125 2650);
PAINT MONO (-2125 2650);
DISPLAY INVISIBLE (-2125 2650);
FORCEPROP 2 LAST CDS_SEC 1
J 0
(-2125 2650);
DISPLAY 1.021277 (-2125 2650);
DISPLAY INVISIBLE (-2125 2650);
FORCEPROP 1 LAST PATH I39
J 0
(-2125 2600);
DISPLAY 0.978723 (-2125 2600);
PAINT WHITE (-2125 2600);
DISPLAY INVISIBLE (-2125 2600);
FORCEADD Q_CAP..1
(-3525 -2225);
FORCEPROP 1 LAST PART_NUMBER CH647KMEA04
J 0
(-3475 -2375);
DISPLAY 0.638298 (-3475 -2375);
DISPLAY INVISIBLE (-3475 -2375);
FORCEPROP 1 LAST VOLTAGE 4V
J 0
(-3475 -2225);
DISPLAY 0.638298 (-3475 -2225);
FORCEPROP 1 LAST VALUE 47UF
J 0
(-3475 -2175);
DISPLAY 0.638298 (-3475 -2175);
FORCEPROP 1 LAST TOLERANCE 20%
J 0
(-3475 -2275);
DISPLAY 0.638298 (-3475 -2275);
FORCEPROP 1 LAST MATERIAL X6S
J 0
(-3475 -2325);
DISPLAY 0.638298 (-3475 -2325);
FORCEPROP 1 LAST PACK_TYPE C0805
J 0
(-3475 -2425);
DISPLAY 0.638298 (-3475 -2425);
FORCEPROP 1 LAST $LOCATION C501
J 0
(-3475 -2125);
DISPLAY 0.978723 (-3475 -2125);
FORCEPROP 1 LASTPIN (-3525 -2125) $PN 1
J 0
(-3515 -2145);
DISPLAY 0.787234 (-3515 -2145);
FORCEPROP 1 LASTPIN (-3525 -2325) $PN 2
J 0
(-3515 -2345);
DISPLAY 0.787234 (-3515 -2345);
FORCEPROP 2 LAST CDS_LIB pure_quanta
J 0
(-3525 -2225);
PAINT MONO (-3525 -2225);
DISPLAY INVISIBLE (-3525 -2225);
FORCEPROP 2 LAST CDS_LOCATION C501
J 0
(-3475 -2025);
DISPLAY 1.021277 (-3475 -2025);
DISPLAY INVISIBLE (-3475 -2025);
FORCEPROP 2 LAST $SEC 1
J 0
(-3475 -2025);
DISPLAY 0.680851 (-3475 -2025);
PAINT MONO (-3475 -2025);
DISPLAY INVISIBLE (-3475 -2025);
FORCEPROP 2 LAST CDS_SEC 1
J 0
(-3475 -2025);
DISPLAY 1.021277 (-3475 -2025);
DISPLAY INVISIBLE (-3475 -2025);
FORCEPROP 1 LAST PATH I4
J 0
(-3475 -2075);
DISPLAY 0.978723 (-3475 -2075);
PAINT WHITE (-3475 -2075);
DISPLAY INVISIBLE (-3475 -2075);
FORCEADD Q_CAP..1
(-1725 2450);
FORCEPROP 1 LAST PART_NUMBER CH647KMEA04
J 0
(-1675 2300);
DISPLAY 0.638298 (-1675 2300);
DISPLAY INVISIBLE (-1675 2300);
FORCEPROP 1 LAST VALUE 47UF
J 0
(-1675 2500);
DISPLAY 0.638298 (-1675 2500);
FORCEPROP 1 LAST VOLTAGE 4V
J 0
(-1675 2450);
DISPLAY 0.638298 (-1675 2450);
FORCEPROP 1 LAST TOLERANCE 20%
J 0
(-1675 2400);
DISPLAY 0.638298 (-1675 2400);
FORCEPROP 1 LAST PACK_TYPE C0805
J 0
(-1675 2250);
DISPLAY 0.638298 (-1675 2250);
FORCEPROP 1 LAST MATERIAL X6S
J 0
(-1675 2350);
DISPLAY 0.638298 (-1675 2350);
FORCEPROP 1 LAST $LOCATION C373
J 0
(-1675 2550);
DISPLAY 0.638298 (-1675 2550);
FORCEPROP 1 LASTPIN (-1725 2550) $PN 1
J 0
(-1715 2530);
DISPLAY 0.787234 (-1715 2530);
FORCEPROP 1 LASTPIN (-1725 2350) $PN 2
J 0
(-1715 2330);
DISPLAY 0.787234 (-1715 2330);
FORCEPROP 2 LAST CDS_LIB pure_quanta
J 0
(-1725 2450);
PAINT MONO (-1725 2450);
DISPLAY INVISIBLE (-1725 2450);
FORCEPROP 1 LAST $LOCATION C373
J 0
(-1675 2650);
DISPLAY 1.021277 (-1675 2650);
DISPLAY INVISIBLE (-1675 2650);
FORCEPROP 2 LAST CDS_LOCATION C373
J 0
(-1675 2650);
DISPLAY 1.021277 (-1675 2650);
DISPLAY INVISIBLE (-1675 2650);
FORCEPROP 2 LAST $SEC 1
J 0
(-1675 2650);
DISPLAY 0.680851 (-1675 2650);
PAINT MONO (-1675 2650);
DISPLAY INVISIBLE (-1675 2650);
FORCEPROP 2 LAST CDS_SEC 1
J 0
(-1675 2650);
DISPLAY 1.021277 (-1675 2650);
DISPLAY INVISIBLE (-1675 2650);
FORCEPROP 1 LAST PATH I40
J 0
(-1675 2600);
DISPLAY 0.978723 (-1675 2600);
PAINT WHITE (-1675 2600);
DISPLAY INVISIBLE (-1675 2600);
FORCEADD Q_CAP..1
(-1275 2450);
FORCEPROP 1 LAST PART_NUMBER CH647KMEA04
J 0
(-1225 2300);
DISPLAY 0.638298 (-1225 2300);
DISPLAY INVISIBLE (-1225 2300);
FORCEPROP 1 LAST VALUE 47UF
J 0
(-1225 2500);
DISPLAY 0.638298 (-1225 2500);
FORCEPROP 1 LAST VOLTAGE 4V
J 0
(-1225 2450);
DISPLAY 0.638298 (-1225 2450);
FORCEPROP 1 LAST TOLERANCE 20%
J 0
(-1225 2400);
DISPLAY 0.638298 (-1225 2400);
FORCEPROP 1 LAST PACK_TYPE C0805
J 0
(-1225 2250);
DISPLAY 0.638298 (-1225 2250);
FORCEPROP 1 LAST MATERIAL X6S
J 0
(-1225 2350);
DISPLAY 0.638298 (-1225 2350);
FORCEPROP 1 LAST $LOCATION C376
J 0
(-1225 2550);
DISPLAY 0.638298 (-1225 2550);
FORCEPROP 1 LASTPIN (-1275 2550) $PN 1
J 0
(-1265 2530);
DISPLAY 0.787234 (-1265 2530);
FORCEPROP 1 LASTPIN (-1275 2350) $PN 2
J 0
(-1265 2330);
DISPLAY 0.787234 (-1265 2330);
FORCEPROP 2 LAST CDS_LIB pure_quanta
J 0
(-1275 2450);
PAINT MONO (-1275 2450);
DISPLAY INVISIBLE (-1275 2450);
FORCEPROP 1 LAST $LOCATION C376
J 0
(-1225 2650);
DISPLAY 1.021277 (-1225 2650);
DISPLAY INVISIBLE (-1225 2650);
FORCEPROP 2 LAST CDS_LOCATION C376
J 0
(-1225 2650);
DISPLAY 1.021277 (-1225 2650);
DISPLAY INVISIBLE (-1225 2650);
FORCEPROP 2 LAST $SEC 1
J 0
(-1225 2650);
DISPLAY 0.680851 (-1225 2650);
PAINT MONO (-1225 2650);
DISPLAY INVISIBLE (-1225 2650);
FORCEPROP 2 LAST CDS_SEC 1
J 0
(-1225 2650);
DISPLAY 1.021277 (-1225 2650);
DISPLAY INVISIBLE (-1225 2650);
FORCEPROP 1 LAST PATH I41
J 0
(-1225 2600);
DISPLAY 0.978723 (-1225 2600);
PAINT WHITE (-1225 2600);
DISPLAY INVISIBLE (-1225 2600);
FORCEADD UNIVERSAL_POWER..1
(325 -950);
FORCEPROP 3 LASTPIN (325 -1000) SIG_NAME PVPP_HBM_CPU0\g
J 0
(335 -990);
DISPLAY 0.659574 (335 -990);
PAINT MONO (335 -990);
DISPLAY INVISIBLE (335 -990);
FORCEPROP 1 LAST HDL_POWER PVPP_HBM_CPU0
J 1
(500 -900);
DISPLAY 0.872340 (500 -900);
PAINT GREEN (500 -900);
FORCEPROP 2 LAST CDS_LIB logical_power
J 0
(325 -950);
PAINT MONO (325 -950);
DISPLAY INVISIBLE (325 -950);
FORCEPROP 1 LAST PATH I42
J 0
(375 -925);
DISPLAY 0.872340 (375 -925);
PAINT AQUA (375 -925);
DISPLAY INVISIBLE (375 -925);
FORCEADD Q_CAP..1
(325 -1225);
FORCEPROP 1 LAST PART_NUMBER CH647KMEA04
J 0
(375 -1375);
DISPLAY 0.638298 (375 -1375);
DISPLAY INVISIBLE (375 -1375);
FORCEPROP 1 LAST TOLERANCE 20%
J 0
(375 -1275);
DISPLAY 0.638298 (375 -1275);
FORCEPROP 1 LAST PACK_TYPE C0805
J 0
(375 -1425);
DISPLAY 0.638298 (375 -1425);
FORCEPROP 1 LAST VALUE 47UF
J 0
(375 -1175);
DISPLAY 0.638298 (375 -1175);
FORCEPROP 1 LAST VOLTAGE 4V
J 0
(375 -1225);
DISPLAY 0.638298 (375 -1225);
FORCEPROP 1 LAST MATERIAL X6S
J 0
(375 -1325);
DISPLAY 0.638298 (375 -1325);
FORCEPROP 1 LAST $LOCATION C1396
J 0
(375 -1125);
DISPLAY 0.978723 (375 -1125);
FORCEPROP 1 LASTPIN (325 -1125) $PN 1
J 0
(335 -1145);
DISPLAY 0.787234 (335 -1145);
FORCEPROP 1 LASTPIN (325 -1325) $PN 2
J 0
(335 -1345);
DISPLAY 0.787234 (335 -1345);
FORCEPROP 2 LAST CDS_LIB pure_quanta
J 0
(325 -1225);
PAINT MONO (325 -1225);
DISPLAY INVISIBLE (325 -1225);
FORCEPROP 2 LAST CDS_LOCATION C1396
J 0
(375 -1025);
DISPLAY 1.021277 (375 -1025);
DISPLAY INVISIBLE (375 -1025);
FORCEPROP 2 LAST $SEC 1
J 0
(375 -1025);
DISPLAY 0.680851 (375 -1025);
PAINT MONO (375 -1025);
DISPLAY INVISIBLE (375 -1025);
FORCEPROP 2 LAST CDS_SEC 1
J 0
(375 -1025);
DISPLAY 1.021277 (375 -1025);
DISPLAY INVISIBLE (375 -1025);
FORCEPROP 1 LAST PATH I43
J 0
(375 -1075);
DISPLAY 0.978723 (375 -1075);
PAINT WHITE (375 -1075);
DISPLAY INVISIBLE (375 -1075);
FORCEADD Q_CAP..1
(775 -1225);
FORCEPROP 1 LAST PART_NUMBER CH647KMEA04
J 0
(825 -1375);
DISPLAY 0.638298 (825 -1375);
DISPLAY INVISIBLE (825 -1375);
FORCEPROP 1 LAST VALUE 47UF
J 0
(825 -1175);
DISPLAY 0.638298 (825 -1175);
FORCEPROP 1 LAST VOLTAGE 4V
J 0
(825 -1225);
DISPLAY 0.638298 (825 -1225);
FORCEPROP 1 LAST TOLERANCE 20%
J 0
(825 -1275);
DISPLAY 0.638298 (825 -1275);
FORCEPROP 1 LAST PACK_TYPE C0805
J 0
(825 -1425);
DISPLAY 0.638298 (825 -1425);
FORCEPROP 1 LAST MATERIAL X6S
J 0
(825 -1325);
DISPLAY 0.638298 (825 -1325);
FORCEPROP 1 LAST $LOCATION C1397
J 0
(825 -1125);
DISPLAY 0.978723 (825 -1125);
FORCEPROP 1 LASTPIN (775 -1125) $PN 1
J 0
(785 -1145);
DISPLAY 0.787234 (785 -1145);
FORCEPROP 1 LASTPIN (775 -1325) $PN 2
J 0
(785 -1345);
DISPLAY 0.787234 (785 -1345);
FORCEPROP 2 LAST CDS_LIB pure_quanta
J 0
(775 -1225);
PAINT MONO (775 -1225);
DISPLAY INVISIBLE (775 -1225);
FORCEPROP 2 LAST CDS_LOCATION C1397
J 0
(825 -1025);
DISPLAY 1.021277 (825 -1025);
DISPLAY INVISIBLE (825 -1025);
FORCEPROP 2 LAST $SEC 1
J 0
(825 -1025);
DISPLAY 0.680851 (825 -1025);
PAINT MONO (825 -1025);
DISPLAY INVISIBLE (825 -1025);
FORCEPROP 2 LAST CDS_SEC 1
J 0
(825 -1025);
DISPLAY 1.021277 (825 -1025);
DISPLAY INVISIBLE (825 -1025);
FORCEPROP 1 LAST PATH I44
J 0
(825 -1075);
DISPLAY 0.978723 (825 -1075);
PAINT WHITE (825 -1075);
DISPLAY INVISIBLE (825 -1075);
FORCEADD UNIVERSAL_POWER..1
(325 100);
FORCEPROP 3 LASTPIN (325 50) SIG_NAME PVNN_MAIN_CPU0\g
J 0
(335 60);
DISPLAY 0.659574 (335 60);
PAINT MONO (335 60);
DISPLAY INVISIBLE (335 60);
FORCEPROP 1 LAST HDL_POWER PVNN_MAIN_CPU0
J 1
(525 150);
DISPLAY 0.872340 (525 150);
PAINT GREEN (525 150);
FORCEPROP 2 LAST CDS_LIB logical_power
J 0
(325 100);
PAINT MONO (325 100);
DISPLAY INVISIBLE (325 100);
FORCEPROP 1 LAST PATH I45
J 0
(375 125);
DISPLAY 0.872340 (375 125);
PAINT AQUA (375 125);
DISPLAY INVISIBLE (375 125);
FORCEADD Q_CAP..1
(325 -175);
FORCEPROP 1 LAST PART_NUMBER CH647KMEA04
J 0
(375 -325);
DISPLAY 0.638298 (375 -325);
DISPLAY INVISIBLE (375 -325);
FORCEPROP 1 LAST PACK_TYPE C0805
J 0
(375 -375);
DISPLAY 0.638298 (375 -375);
FORCEPROP 1 LAST VALUE 47UF
J 0
(375 -125);
DISPLAY 0.638298 (375 -125);
FORCEPROP 1 LAST VOLTAGE 4V
J 0
(375 -175);
DISPLAY 0.638298 (375 -175);
FORCEPROP 1 LAST MATERIAL X6S
J 0
(375 -275);
DISPLAY 0.638298 (375 -275);
FORCEPROP 1 LAST TOLERANCE 20%
J 0
(375 -225);
DISPLAY 0.638298 (375 -225);
FORCEPROP 1 LAST $LOCATION C395
J 0
(375 -75);
DISPLAY 0.638298 (375 -75);
FORCEPROP 1 LASTPIN (325 -75) $PN 1
J 0
(335 -95);
DISPLAY 0.787234 (335 -95);
FORCEPROP 1 LASTPIN (325 -275) $PN 2
J 0
(335 -295);
DISPLAY 0.787234 (335 -295);
FORCEPROP 2 LAST CDS_LIB pure_quanta
J 0
(325 -175);
PAINT MONO (325 -175);
DISPLAY INVISIBLE (325 -175);
FORCEPROP 1 LAST $LOCATION C395
J 0
(375 25);
DISPLAY 1.021277 (375 25);
DISPLAY INVISIBLE (375 25);
FORCEPROP 2 LAST CDS_LOCATION C395
J 0
(375 25);
DISPLAY 1.021277 (375 25);
DISPLAY INVISIBLE (375 25);
FORCEPROP 2 LAST $SEC 1
J 0
(375 25);
DISPLAY 0.680851 (375 25);
PAINT MONO (375 25);
DISPLAY INVISIBLE (375 25);
FORCEPROP 2 LAST CDS_SEC 1
J 0
(375 25);
DISPLAY 1.021277 (375 25);
DISPLAY INVISIBLE (375 25);
FORCEPROP 1 LAST PATH I46
J 0
(375 -25);
DISPLAY 0.978723 (375 -25);
PAINT WHITE (375 -25);
DISPLAY INVISIBLE (375 -25);
FORCEADD Q_CAP..1
(775 -175);
FORCEPROP 1 LAST PART_NUMBER CH647LME900
J 0
(825 -325);
DISPLAY 0.638298 (825 -325);
DISPLAY INVISIBLE (825 -325);
FORCEPROP 1 LAST VALUE 47UF
J 0
(825 -125);
DISPLAY 0.638298 (825 -125);
FORCEPROP 1 LAST VOLTAGE 2.5V
J 0
(825 -175);
DISPLAY 0.638298 (825 -175);
FORCEPROP 1 LAST TOLERANCE 20%
J 0
(825 -225);
DISPLAY 0.638298 (825 -225);
FORCEPROP 1 LAST PACK_TYPE C0603
J 0
(825 -375);
DISPLAY 0.638298 (825 -375);
FORCEPROP 1 LAST MATERIAL X6S
J 0
(825 -275);
DISPLAY 0.638298 (825 -275);
FORCEPROP 1 LAST $LOCATION C1405
J 0
(825 -75);
DISPLAY 0.978723 (825 -75);
FORCEPROP 1 LASTPIN (775 -75) $PN 1
J 0
(785 -95);
DISPLAY 0.787234 (785 -95);
FORCEPROP 1 LASTPIN (775 -275) $PN 2
J 0
(785 -295);
DISPLAY 0.787234 (785 -295);
FORCEPROP 2 LAST CDS_LIB pure_quanta
J 0
(775 -175);
PAINT MONO (775 -175);
DISPLAY INVISIBLE (775 -175);
FORCEPROP 2 LAST CDS_LOCATION C1405
J 0
(825 25);
DISPLAY 1.021277 (825 25);
DISPLAY INVISIBLE (825 25);
FORCEPROP 2 LAST $SEC 1
J 0
(825 25);
DISPLAY 0.680851 (825 25);
PAINT MONO (825 25);
DISPLAY INVISIBLE (825 25);
FORCEPROP 2 LAST CDS_SEC 1
J 0
(825 25);
DISPLAY 1.021277 (825 25);
DISPLAY INVISIBLE (825 25);
FORCEPROP 1 LAST PATH I47
J 0
(825 -25);
DISPLAY 0.978723 (825 -25);
PAINT WHITE (825 -25);
DISPLAY INVISIBLE (825 -25);
FORCEADD Q_CAP..1
(-825 1725);
FORCEPROP 1 LAST PART_NUMBER CH647KMEA04
J 0
(-775 1575);
DISPLAY 0.638298 (-775 1575);
DISPLAY INVISIBLE (-775 1575);
FORCEPROP 1 LAST VALUE 47UF
J 0
(-775 1775);
DISPLAY 0.638298 (-775 1775);
FORCEPROP 1 LAST VOLTAGE 4V
J 0
(-775 1725);
DISPLAY 0.638298 (-775 1725);
FORCEPROP 1 LAST TOLERANCE 20%
J 0
(-775 1675);
DISPLAY 0.638298 (-775 1675);
FORCEPROP 1 LAST PACK_TYPE C0805
J 0
(-775 1525);
DISPLAY 0.638298 (-775 1525);
FORCEPROP 1 LAST MATERIAL X6S
J 0
(-775 1625);
DISPLAY 0.638298 (-775 1625);
FORCEPROP 1 LAST $LOCATION C389
J 0
(-775 1825);
DISPLAY 0.638298 (-775 1825);
FORCEPROP 1 LASTPIN (-825 1825) $PN 1
J 0
(-815 1805);
DISPLAY 0.787234 (-815 1805);
FORCEPROP 1 LASTPIN (-825 1625) $PN 2
J 0
(-815 1605);
DISPLAY 0.787234 (-815 1605);
FORCEPROP 2 LAST CDS_LIB pure_quanta
J 0
(-825 1725);
PAINT MONO (-825 1725);
DISPLAY INVISIBLE (-825 1725);
FORCEPROP 1 LAST $LOCATION C389
J 0
(-775 1925);
DISPLAY 1.021277 (-775 1925);
DISPLAY INVISIBLE (-775 1925);
FORCEPROP 2 LAST CDS_LOCATION C389
J 0
(-775 1925);
DISPLAY 1.021277 (-775 1925);
DISPLAY INVISIBLE (-775 1925);
FORCEPROP 2 LAST $SEC 1
J 0
(-775 1925);
DISPLAY 0.680851 (-775 1925);
PAINT MONO (-775 1925);
DISPLAY INVISIBLE (-775 1925);
FORCEPROP 2 LAST CDS_SEC 1
J 0
(-775 1925);
DISPLAY 1.021277 (-775 1925);
DISPLAY INVISIBLE (-775 1925);
FORCEPROP 1 LAST PATH I48
J 0
(-775 1875);
DISPLAY 0.978723 (-775 1875);
PAINT WHITE (-775 1875);
DISPLAY INVISIBLE (-775 1875);
FORCEADD Q_CAP..1
(-375 1725);
FORCEPROP 1 LAST PART_NUMBER CH647KMEA04
J 0
(-325 1575);
DISPLAY 0.638298 (-325 1575);
DISPLAY INVISIBLE (-325 1575);
FORCEPROP 1 LAST TOLERANCE 20%
J 0
(-325 1675);
DISPLAY 0.638298 (-325 1675);
FORCEPROP 1 LAST VALUE 47UF
J 0
(-325 1775);
DISPLAY 0.638298 (-325 1775);
FORCEPROP 1 LAST VOLTAGE 4V
J 0
(-325 1725);
DISPLAY 0.638298 (-325 1725);
FORCEPROP 1 LAST PACK_TYPE C0805
J 0
(-325 1525);
DISPLAY 0.638298 (-325 1525);
FORCEPROP 1 LAST MATERIAL X6S
J 0
(-325 1625);
DISPLAY 0.638298 (-325 1625);
FORCEPROP 1 LAST $LOCATION C391
J 0
(-325 1825);
DISPLAY 0.638298 (-325 1825);
FORCEPROP 1 LASTPIN (-375 1825) $PN 1
J 0
(-365 1805);
DISPLAY 0.787234 (-365 1805);
FORCEPROP 1 LASTPIN (-375 1625) $PN 2
J 0
(-365 1605);
DISPLAY 0.787234 (-365 1605);
FORCEPROP 2 LAST CDS_LIB pure_quanta
J 0
(-375 1725);
PAINT MONO (-375 1725);
DISPLAY INVISIBLE (-375 1725);
FORCEPROP 1 LAST $LOCATION C391
J 0
(-325 1925);
DISPLAY 1.021277 (-325 1925);
DISPLAY INVISIBLE (-325 1925);
FORCEPROP 2 LAST CDS_LOCATION C391
J 0
(-325 1925);
DISPLAY 1.021277 (-325 1925);
DISPLAY INVISIBLE (-325 1925);
FORCEPROP 2 LAST $SEC 1
J 0
(-325 1925);
DISPLAY 0.680851 (-325 1925);
PAINT MONO (-325 1925);
DISPLAY INVISIBLE (-325 1925);
FORCEPROP 2 LAST CDS_SEC 1
J 0
(-325 1925);
DISPLAY 1.021277 (-325 1925);
DISPLAY INVISIBLE (-325 1925);
FORCEPROP 1 LAST PATH I49
J 0
(-325 1875);
DISPLAY 0.978723 (-325 1875);
PAINT WHITE (-325 1875);
DISPLAY INVISIBLE (-325 1875);
FORCEADD UNIVERSAL_GND..1
(-2625 -2575);
FORCEPROP 3 LASTPIN (-2625 -2525) SIG_NAME GND\g
J 0
(-2615 -2515);
DISPLAY 0.659574 (-2615 -2515);
PAINT MONO (-2615 -2515);
DISPLAY INVISIBLE (-2615 -2515);
FORCEPROP 2 LAST CDS_LIB logical_power
J 0
(-2625 -2575);
PAINT MONO (-2625 -2575);
DISPLAY INVISIBLE (-2625 -2575);
FORCEPROP 1 LAST HDL_POWER GND
J 1
(-2600 -2650);
DISPLAY 0.872340 (-2600 -2650);
PAINT GREEN (-2600 -2650);
DISPLAY INVISIBLE (-2600 -2650);
FORCEPROP 1 LAST PATH I5
J 0
(-2550 -2575);
DISPLAY 0.872340 (-2550 -2575);
PAINT AQUA (-2550 -2575);
DISPLAY INVISIBLE (-2550 -2575);
FORCEADD Q_CAP..1
(-825 2450);
FORCEPROP 1 LAST PART_NUMBER CH647KMEA04
J 0
(-775 2300);
DISPLAY 0.638298 (-775 2300);
DISPLAY INVISIBLE (-775 2300);
FORCEPROP 1 LAST VALUE 47UF
J 0
(-775 2500);
DISPLAY 0.638298 (-775 2500);
FORCEPROP 1 LAST VOLTAGE 4V
J 0
(-775 2450);
DISPLAY 0.638298 (-775 2450);
FORCEPROP 1 LAST TOLERANCE 20%
J 0
(-775 2400);
DISPLAY 0.638298 (-775 2400);
FORCEPROP 1 LAST PACK_TYPE C0805
J 0
(-775 2250);
DISPLAY 0.638298 (-775 2250);
FORCEPROP 1 LAST MATERIAL X6S
J 0
(-775 2350);
DISPLAY 0.638298 (-775 2350);
FORCEPROP 1 LAST $LOCATION C379
J 0
(-775 2550);
DISPLAY 0.638298 (-775 2550);
FORCEPROP 1 LASTPIN (-825 2550) $PN 1
J 0
(-815 2530);
DISPLAY 0.787234 (-815 2530);
FORCEPROP 1 LASTPIN (-825 2350) $PN 2
J 0
(-815 2330);
DISPLAY 0.787234 (-815 2330);
FORCEPROP 2 LAST CDS_LIB pure_quanta
J 0
(-825 2450);
PAINT MONO (-825 2450);
DISPLAY INVISIBLE (-825 2450);
FORCEPROP 1 LAST $LOCATION C379
J 0
(-775 2650);
DISPLAY 1.021277 (-775 2650);
DISPLAY INVISIBLE (-775 2650);
FORCEPROP 2 LAST CDS_LOCATION C379
J 0
(-775 2650);
DISPLAY 1.021277 (-775 2650);
DISPLAY INVISIBLE (-775 2650);
FORCEPROP 2 LAST $SEC 1
J 0
(-775 2650);
DISPLAY 0.680851 (-775 2650);
PAINT MONO (-775 2650);
DISPLAY INVISIBLE (-775 2650);
FORCEPROP 2 LAST CDS_SEC 1
J 0
(-775 2650);
DISPLAY 1.021277 (-775 2650);
DISPLAY INVISIBLE (-775 2650);
FORCEPROP 1 LAST PATH I50
J 0
(-775 2600);
DISPLAY 0.978723 (-775 2600);
PAINT WHITE (-775 2600);
DISPLAY INVISIBLE (-775 2600);
FORCEADD Q_CAP..1
(-375 2450);
FORCEPROP 1 LAST PART_NUMBER CH647KMEA04
J 0
(-325 2300);
DISPLAY 0.638298 (-325 2300);
DISPLAY INVISIBLE (-325 2300);
FORCEPROP 1 LAST VALUE 47UF
J 0
(-325 2500);
DISPLAY 0.638298 (-325 2500);
FORCEPROP 1 LAST VOLTAGE 4V
J 0
(-325 2450);
DISPLAY 0.638298 (-325 2450);
FORCEPROP 1 LAST TOLERANCE 20%
J 0
(-325 2400);
DISPLAY 0.638298 (-325 2400);
FORCEPROP 1 LAST PACK_TYPE C0805
J 0
(-325 2250);
DISPLAY 0.638298 (-325 2250);
FORCEPROP 1 LAST MATERIAL X6S
J 0
(-325 2350);
DISPLAY 0.638298 (-325 2350);
FORCEPROP 1 LAST $LOCATION C382
J 0
(-325 2550);
DISPLAY 0.638298 (-325 2550);
FORCEPROP 1 LASTPIN (-375 2550) $PN 1
J 0
(-365 2530);
DISPLAY 0.787234 (-365 2530);
FORCEPROP 1 LASTPIN (-375 2350) $PN 2
J 0
(-365 2330);
DISPLAY 0.787234 (-365 2330);
FORCEPROP 2 LAST CDS_LIB pure_quanta
J 0
(-375 2450);
PAINT MONO (-375 2450);
DISPLAY INVISIBLE (-375 2450);
FORCEPROP 1 LAST $LOCATION C382
J 0
(-325 2650);
DISPLAY 1.021277 (-325 2650);
DISPLAY INVISIBLE (-325 2650);
FORCEPROP 2 LAST CDS_LOCATION C382
J 0
(-325 2650);
DISPLAY 1.021277 (-325 2650);
DISPLAY INVISIBLE (-325 2650);
FORCEPROP 2 LAST $SEC 1
J 0
(-325 2650);
DISPLAY 0.680851 (-325 2650);
PAINT MONO (-325 2650);
DISPLAY INVISIBLE (-325 2650);
FORCEPROP 2 LAST CDS_SEC 1
J 0
(-325 2650);
DISPLAY 1.021277 (-325 2650);
DISPLAY INVISIBLE (-325 2650);
FORCEPROP 1 LAST PATH I51
J 0
(-325 2600);
DISPLAY 0.978723 (-325 2600);
PAINT WHITE (-325 2600);
DISPLAY INVISIBLE (-325 2600);
FORCEADD Q_CAP..1
(75 1725);
FORCEPROP 1 LAST PART_NUMBER CH647KMEA04
J 0
(125 1575);
DISPLAY 0.638298 (125 1575);
DISPLAY INVISIBLE (125 1575);
FORCEPROP 1 LAST VALUE 47UF
J 0
(125 1775);
DISPLAY 0.638298 (125 1775);
FORCEPROP 1 LAST VOLTAGE 4V
J 0
(125 1725);
DISPLAY 0.638298 (125 1725);
FORCEPROP 1 LAST TOLERANCE 20%
J 0
(125 1675);
DISPLAY 0.638298 (125 1675);
FORCEPROP 1 LAST PACK_TYPE C0805
J 0
(125 1525);
DISPLAY 0.638298 (125 1525);
FORCEPROP 1 LAST MATERIAL X6S
J 0
(125 1625);
DISPLAY 0.638298 (125 1625);
FORCEPROP 1 LAST $LOCATION C393
J 0
(125 1825);
DISPLAY 0.638298 (125 1825);
FORCEPROP 1 LASTPIN (75 1825) $PN 1
J 0
(85 1805);
DISPLAY 0.787234 (85 1805);
FORCEPROP 1 LASTPIN (75 1625) $PN 2
J 0
(85 1605);
DISPLAY 0.787234 (85 1605);
FORCEPROP 2 LAST CDS_LIB pure_quanta
J 0
(75 1725);
PAINT MONO (75 1725);
DISPLAY INVISIBLE (75 1725);
FORCEPROP 1 LAST $LOCATION C393
J 0
(125 1925);
DISPLAY 1.021277 (125 1925);
DISPLAY INVISIBLE (125 1925);
FORCEPROP 2 LAST CDS_LOCATION C393
J 0
(125 1925);
DISPLAY 1.021277 (125 1925);
DISPLAY INVISIBLE (125 1925);
FORCEPROP 2 LAST $SEC 1
J 0
(125 1925);
DISPLAY 0.680851 (125 1925);
PAINT MONO (125 1925);
DISPLAY INVISIBLE (125 1925);
FORCEPROP 2 LAST CDS_SEC 1
J 0
(125 1925);
DISPLAY 1.021277 (125 1925);
DISPLAY INVISIBLE (125 1925);
FORCEPROP 1 LAST PATH I52
J 0
(125 1875);
DISPLAY 0.978723 (125 1875);
PAINT WHITE (125 1875);
DISPLAY INVISIBLE (125 1875);
FORCEADD UNIVERSAL_GND..1
(525 1375);
FORCEPROP 3 LASTPIN (525 1425) SIG_NAME GND\g
J 0
(535 1435);
DISPLAY 0.659574 (535 1435);
PAINT MONO (535 1435);
DISPLAY INVISIBLE (535 1435);
FORCEPROP 2 LAST CDS_LIB logical_power
J 0
(525 1375);
PAINT MONO (525 1375);
DISPLAY INVISIBLE (525 1375);
FORCEPROP 1 LAST HDL_POWER GND
J 1
(550 1300);
DISPLAY 0.872340 (550 1300);
PAINT GREEN (550 1300);
DISPLAY INVISIBLE (550 1300);
FORCEPROP 1 LAST PATH I53
J 0
(600 1375);
DISPLAY 0.872340 (600 1375);
PAINT AQUA (600 1375);
DISPLAY INVISIBLE (600 1375);
FORCEADD Q_CAP..1
(525 1725);
FORCEPROP 1 LAST PART_NUMBER CH647KMEA04
J 0
(575 1575);
DISPLAY 0.638298 (575 1575);
DISPLAY INVISIBLE (575 1575);
FORCEPROP 1 LAST VOLTAGE 4V
J 0
(575 1725);
DISPLAY 0.638298 (575 1725);
FORCEPROP 1 LAST TOLERANCE 20%
J 0
(575 1675);
DISPLAY 0.638298 (575 1675);
FORCEPROP 1 LAST VALUE 47UF
J 0
(575 1775);
DISPLAY 0.638298 (575 1775);
FORCEPROP 1 LAST PACK_TYPE C0805
J 0
(575 1525);
DISPLAY 0.638298 (575 1525);
FORCEPROP 1 LAST MATERIAL X6S
J 0
(575 1625);
DISPLAY 0.638298 (575 1625);
FORCEPROP 1 LAST $LOCATION C360
J 0
(575 1825);
DISPLAY 0.787234 (575 1825);
FORCEPROP 1 LASTPIN (525 1825) $PN 1
J 0
(535 1805);
DISPLAY 0.787234 (535 1805);
FORCEPROP 1 LASTPIN (525 1625) $PN 2
J 0
(535 1605);
DISPLAY 0.787234 (535 1605);
FORCEPROP 2 LAST CDS_LIB pure_quanta
J 0
(525 1725);
PAINT MONO (525 1725);
DISPLAY INVISIBLE (525 1725);
FORCEPROP 0 LAST CDS_LOCATION C360
J 0
(575 1875);
DISPLAY 1.021277 (575 1875);
DISPLAY INVISIBLE (575 1875);
FORCEPROP 2 LAST $SEC 1
J 0
(575 1925);
DISPLAY 0.680851 (575 1925);
PAINT MONO (575 1925);
DISPLAY INVISIBLE (575 1925);
FORCEPROP 2 LAST CDS_SEC 1
J 0
(575 1925);
DISPLAY 1.021277 (575 1925);
DISPLAY INVISIBLE (575 1925);
FORCEPROP 1 LAST PATH I54
J 0
(575 1875);
DISPLAY 0.978723 (575 1875);
PAINT WHITE (575 1875);
DISPLAY INVISIBLE (575 1875);
FORCEADD Q_CAP..1
(75 2450);
FORCEPROP 1 LAST PART_NUMBER CH647KMEA04
J 0
(125 2300);
DISPLAY 0.638298 (125 2300);
DISPLAY INVISIBLE (125 2300);
FORCEPROP 1 LAST VALUE 47UF
J 0
(125 2500);
DISPLAY 0.638298 (125 2500);
FORCEPROP 1 LAST VOLTAGE 4V
J 0
(125 2450);
DISPLAY 0.638298 (125 2450);
FORCEPROP 1 LAST TOLERANCE 20%
J 0
(125 2400);
DISPLAY 0.638298 (125 2400);
FORCEPROP 1 LAST PACK_TYPE C0805
J 0
(125 2250);
DISPLAY 0.638298 (125 2250);
FORCEPROP 1 LAST MATERIAL X6S
J 0
(125 2350);
DISPLAY 0.638298 (125 2350);
FORCEPROP 1 LAST $LOCATION C385
J 0
(125 2550);
DISPLAY 0.638298 (125 2550);
FORCEPROP 1 LASTPIN (75 2550) $PN 1
J 0
(85 2530);
DISPLAY 0.787234 (85 2530);
FORCEPROP 1 LASTPIN (75 2350) $PN 2
J 0
(85 2330);
DISPLAY 0.787234 (85 2330);
FORCEPROP 2 LAST CDS_LIB pure_quanta
J 0
(75 2450);
PAINT MONO (75 2450);
DISPLAY INVISIBLE (75 2450);
FORCEPROP 1 LAST $LOCATION C385
J 0
(125 2650);
DISPLAY 1.021277 (125 2650);
DISPLAY INVISIBLE (125 2650);
FORCEPROP 2 LAST CDS_LOCATION C385
J 0
(125 2650);
DISPLAY 1.021277 (125 2650);
DISPLAY INVISIBLE (125 2650);
FORCEPROP 2 LAST $SEC 1
J 0
(125 2650);
DISPLAY 0.680851 (125 2650);
PAINT MONO (125 2650);
DISPLAY INVISIBLE (125 2650);
FORCEPROP 2 LAST CDS_SEC 1
J 0
(125 2650);
DISPLAY 1.021277 (125 2650);
DISPLAY INVISIBLE (125 2650);
FORCEPROP 1 LAST PATH I55
J 0
(125 2600);
DISPLAY 0.978723 (125 2600);
PAINT WHITE (125 2600);
DISPLAY INVISIBLE (125 2600);
FORCEADD Q_CAP..1
(525 2450);
FORCEPROP 1 LAST PART_NUMBER CH647KMEA04
J 0
(575 2300);
DISPLAY 0.638298 (575 2300);
DISPLAY INVISIBLE (575 2300);
FORCEPROP 1 LAST VALUE 47UF
J 0
(575 2500);
DISPLAY 0.638298 (575 2500);
FORCEPROP 1 LAST VOLTAGE 4V
J 0
(575 2450);
DISPLAY 0.638298 (575 2450);
FORCEPROP 1 LAST TOLERANCE 20%
J 0
(575 2400);
DISPLAY 0.638298 (575 2400);
FORCEPROP 1 LAST PACK_TYPE C0805
J 0
(575 2250);
DISPLAY 0.638298 (575 2250);
FORCEPROP 1 LAST MATERIAL X6S
J 0
(575 2350);
DISPLAY 0.638298 (575 2350);
FORCEPROP 1 LAST $LOCATION C387
J 0
(575 2550);
DISPLAY 0.638298 (575 2550);
FORCEPROP 1 LASTPIN (525 2550) $PN 1
J 0
(535 2530);
DISPLAY 0.787234 (535 2530);
FORCEPROP 1 LASTPIN (525 2350) $PN 2
J 0
(535 2330);
DISPLAY 0.787234 (535 2330);
FORCEPROP 2 LAST CDS_LIB pure_quanta
J 0
(525 2450);
PAINT MONO (525 2450);
DISPLAY INVISIBLE (525 2450);
FORCEPROP 1 LAST $LOCATION C387
J 0
(575 2650);
DISPLAY 1.021277 (575 2650);
DISPLAY INVISIBLE (575 2650);
FORCEPROP 2 LAST CDS_LOCATION C387
J 0
(575 2650);
DISPLAY 1.021277 (575 2650);
DISPLAY INVISIBLE (575 2650);
FORCEPROP 2 LAST $SEC 1
J 0
(575 2650);
DISPLAY 0.680851 (575 2650);
PAINT MONO (575 2650);
DISPLAY INVISIBLE (575 2650);
FORCEPROP 2 LAST CDS_SEC 1
J 0
(575 2650);
DISPLAY 1.021277 (575 2650);
DISPLAY INVISIBLE (575 2650);
FORCEPROP 1 LAST PATH I56
J 0
(575 2600);
DISPLAY 0.978723 (575 2600);
PAINT WHITE (575 2600);
DISPLAY INVISIBLE (575 2600);
FORCEADD UNIVERSAL_GND..1
(1675 -1575);
FORCEPROP 3 LASTPIN (1675 -1525) SIG_NAME GND\g
J 0
(1685 -1515);
DISPLAY 0.659574 (1685 -1515);
PAINT MONO (1685 -1515);
DISPLAY INVISIBLE (1685 -1515);
FORCEPROP 2 LAST CDS_LIB logical_power
J 0
(1675 -1575);
DISPLAY INVISIBLE (1675 -1575);
FORCEPROP 1 LAST HDL_POWER GND
J 1
(1700 -1650);
DISPLAY 0.872340 (1700 -1650);
PAINT GREEN (1700 -1650);
DISPLAY INVISIBLE (1700 -1650);
FORCEPROP 1 LAST PATH I57
J 0
(1750 -1575);
DISPLAY 0.872340 (1750 -1575);
PAINT AQUA (1750 -1575);
DISPLAY INVISIBLE (1750 -1575);
FORCEADD Q_CAP..1
(1225 -1225);
FORCEPROP 1 LAST PART_NUMBER CH647KMEA04
J 0
(1275 -1375);
DISPLAY 0.638298 (1275 -1375);
DISPLAY INVISIBLE (1275 -1375);
FORCEPROP 1 LAST VALUE 47UF
J 0
(1275 -1175);
DISPLAY 0.638298 (1275 -1175);
FORCEPROP 1 LAST VOLTAGE 4V
J 0
(1275 -1225);
DISPLAY 0.638298 (1275 -1225);
FORCEPROP 1 LAST TOLERANCE 20%
J 0
(1275 -1275);
DISPLAY 0.638298 (1275 -1275);
FORCEPROP 1 LAST MATERIAL X6S
J 0
(1275 -1325);
DISPLAY 0.638298 (1275 -1325);
FORCEPROP 1 LAST PACK_TYPE C0805
J 0
(1275 -1425);
DISPLAY 0.638298 (1275 -1425);
FORCEPROP 1 LAST $LOCATION C1398
J 0
(1275 -1125);
DISPLAY 0.978723 (1275 -1125);
FORCEPROP 1 LASTPIN (1225 -1125) $PN 1
J 0
(1235 -1145);
DISPLAY 0.787234 (1235 -1145);
FORCEPROP 1 LASTPIN (1225 -1325) $PN 2
J 0
(1235 -1345);
DISPLAY 0.787234 (1235 -1345);
FORCEPROP 2 LAST CDS_LIB pure_quanta
J 0
(1225 -1225);
PAINT MONO (1225 -1225);
DISPLAY INVISIBLE (1225 -1225);
FORCEPROP 2 LAST CDS_LOCATION C1398
J 0
(1275 -1025);
DISPLAY 1.021277 (1275 -1025);
DISPLAY INVISIBLE (1275 -1025);
FORCEPROP 2 LAST $SEC 1
J 0
(1275 -1025);
DISPLAY 0.680851 (1275 -1025);
PAINT MONO (1275 -1025);
DISPLAY INVISIBLE (1275 -1025);
FORCEPROP 2 LAST CDS_SEC 1
J 0
(1275 -1025);
DISPLAY 1.021277 (1275 -1025);
DISPLAY INVISIBLE (1275 -1025);
FORCEPROP 1 LAST PATH I58
J 0
(1275 -1075);
DISPLAY 0.978723 (1275 -1075);
PAINT WHITE (1275 -1075);
DISPLAY INVISIBLE (1275 -1075);
FORCEADD Q_CAP..1
(1675 -1225);
FORCEPROP 1 LAST PART_NUMBER CH4221KEE00
J 0
(1725 -1375);
DISPLAY 0.638298 (1725 -1375);
DISPLAY INVISIBLE (1725 -1375);
FORCEPROP 1 LAST VALUE 0.22UF
J 0
(1725 -1175);
DISPLAY 0.638298 (1725 -1175);
FORCEPROP 1 LAST MATERIAL X6S
J 0
(1725 -1325);
DISPLAY 0.638298 (1725 -1325);
FORCEPROP 1 LAST VOLTAGE 6.3V
J 0
(1725 -1225);
DISPLAY 0.638298 (1725 -1225);
FORCEPROP 1 LAST TOLERANCE 10%
J 0
(1725 -1275);
DISPLAY 0.638298 (1725 -1275);
FORCEPROP 1 LAST PACK_TYPE C0201
J 0
(1725 -1425);
DISPLAY 0.638298 (1725 -1425);
FORCEPROP 1 LAST $LOCATION C1436
J 0
(1725 -1125);
DISPLAY 0.978723 (1725 -1125);
FORCEPROP 1 LASTPIN (1675 -1125) $PN 1
J 0
(1685 -1145);
DISPLAY 0.787234 (1685 -1145);
PAINT MONO (1685 -1145);
FORCEPROP 1 LASTPIN (1675 -1325) $PN 2
J 0
(1685 -1345);
DISPLAY 0.787234 (1685 -1345);
PAINT MONO (1685 -1345);
FORCEPROP 2 LAST CDS_LIB pure_quanta
J 0
(1675 -1225);
DISPLAY INVISIBLE (1675 -1225);
FORCEPROP 0 LAST CDS_LOCATION C1436
J 0
(1725 -1075);
DISPLAY 1.021277 (1725 -1075);
DISPLAY INVISIBLE (1725 -1075);
FORCEPROP 0 LAST $SEC 1
J 0
(1725 -1075);
DISPLAY 0.680851 (1725 -1075);
PAINT MONO (1725 -1075);
DISPLAY INVISIBLE (1725 -1075);
FORCEPROP 0 LAST CDS_SEC 1
J 0
(1725 -1075);
DISPLAY 1.021277 (1725 -1075);
DISPLAY INVISIBLE (1725 -1075);
FORCEPROP 1 LAST PATH I59
J 0
(1725 -1075);
DISPLAY 0.978723 (1725 -1075);
PAINT WHITE (1725 -1075);
DISPLAY INVISIBLE (1725 -1075);
FORCEADD Q_CAP..1
(-3075 -2225);
FORCEPROP 1 LAST PART_NUMBER CH647KMEA04
J 0
(-3025 -2375);
DISPLAY 0.638298 (-3025 -2375);
DISPLAY INVISIBLE (-3025 -2375);
FORCEPROP 1 LAST VOLTAGE 4V
J 0
(-3025 -2225);
DISPLAY 0.638298 (-3025 -2225);
FORCEPROP 1 LAST TOLERANCE 20%
J 0
(-3025 -2275);
DISPLAY 0.638298 (-3025 -2275);
FORCEPROP 1 LAST PACK_TYPE C0805
J 0
(-3025 -2425);
DISPLAY 0.638298 (-3025 -2425);
FORCEPROP 1 LAST VALUE 47UF
J 0
(-3025 -2175);
DISPLAY 0.638298 (-3025 -2175);
FORCEPROP 1 LAST MATERIAL X6S
J 0
(-3025 -2325);
DISPLAY 0.638298 (-3025 -2325);
FORCEPROP 1 LAST $LOCATION C505
J 0
(-3025 -2125);
DISPLAY 0.978723 (-3025 -2125);
FORCEPROP 1 LASTPIN (-3075 -2125) $PN 1
J 0
(-3065 -2145);
DISPLAY 0.787234 (-3065 -2145);
FORCEPROP 1 LASTPIN (-3075 -2325) $PN 2
J 0
(-3065 -2345);
DISPLAY 0.787234 (-3065 -2345);
FORCEPROP 2 LAST CDS_LIB pure_quanta
J 0
(-3075 -2225);
PAINT MONO (-3075 -2225);
DISPLAY INVISIBLE (-3075 -2225);
FORCEPROP 2 LAST CDS_LOCATION C505
J 0
(-3025 -2025);
DISPLAY 1.021277 (-3025 -2025);
DISPLAY INVISIBLE (-3025 -2025);
FORCEPROP 2 LAST $SEC 1
J 0
(-3025 -2025);
DISPLAY 0.680851 (-3025 -2025);
PAINT MONO (-3025 -2025);
DISPLAY INVISIBLE (-3025 -2025);
FORCEPROP 2 LAST CDS_SEC 1
J 0
(-3025 -2025);
DISPLAY 1.021277 (-3025 -2025);
DISPLAY INVISIBLE (-3025 -2025);
FORCEPROP 1 LAST PATH I6
J 0
(-3025 -2075);
DISPLAY 0.978723 (-3025 -2075);
PAINT WHITE (-3025 -2075);
DISPLAY INVISIBLE (-3025 -2075);
FORCEADD UNIVERSAL_GND..1
(1675 -525);
FORCEPROP 3 LASTPIN (1675 -475) SIG_NAME GND\g
J 0
(1685 -465);
DISPLAY 0.659574 (1685 -465);
PAINT MONO (1685 -465);
DISPLAY INVISIBLE (1685 -465);
FORCEPROP 2 LAST CDS_LIB logical_power
J 0
(1675 -525);
PAINT MONO (1675 -525);
DISPLAY INVISIBLE (1675 -525);
FORCEPROP 1 LAST HDL_POWER GND
J 1
(1700 -600);
DISPLAY 0.872340 (1700 -600);
PAINT GREEN (1700 -600);
DISPLAY INVISIBLE (1700 -600);
FORCEPROP 1 LAST PATH I60
J 0
(1750 -525);
DISPLAY 0.872340 (1750 -525);
PAINT AQUA (1750 -525);
DISPLAY INVISIBLE (1750 -525);
FORCEADD Q_CAP..1
(1225 -175);
FORCEPROP 1 LAST PART_NUMBER CH647LME900
J 0
(1275 -325);
DISPLAY 0.638298 (1275 -325);
DISPLAY INVISIBLE (1275 -325);
FORCEPROP 1 LAST VALUE 47UF
J 0
(1275 -125);
DISPLAY 0.638298 (1275 -125);
FORCEPROP 1 LAST VOLTAGE 2.5V
J 0
(1275 -175);
DISPLAY 0.638298 (1275 -175);
FORCEPROP 1 LAST TOLERANCE 20%
J 0
(1275 -225);
DISPLAY 0.638298 (1275 -225);
FORCEPROP 1 LAST PACK_TYPE C0603
J 0
(1275 -375);
DISPLAY 0.638298 (1275 -375);
FORCEPROP 1 LAST MATERIAL X6S
J 0
(1275 -275);
DISPLAY 0.638298 (1275 -275);
FORCEPROP 1 LAST $LOCATION C1406
J 0
(1275 -75);
DISPLAY 0.978723 (1275 -75);
FORCEPROP 1 LASTPIN (1225 -75) $PN 1
J 0
(1235 -95);
DISPLAY 0.787234 (1235 -95);
FORCEPROP 1 LASTPIN (1225 -275) $PN 2
J 0
(1235 -295);
DISPLAY 0.787234 (1235 -295);
FORCEPROP 2 LAST CDS_LIB pure_quanta
J 0
(1225 -175);
PAINT MONO (1225 -175);
DISPLAY INVISIBLE (1225 -175);
FORCEPROP 2 LAST CDS_LOCATION C1406
J 0
(1275 25);
DISPLAY 1.021277 (1275 25);
DISPLAY INVISIBLE (1275 25);
FORCEPROP 2 LAST $SEC 1
J 0
(1275 25);
DISPLAY 0.680851 (1275 25);
PAINT MONO (1275 25);
DISPLAY INVISIBLE (1275 25);
FORCEPROP 2 LAST CDS_SEC 1
J 0
(1275 25);
DISPLAY 1.021277 (1275 25);
DISPLAY INVISIBLE (1275 25);
FORCEPROP 1 LAST PATH I61
J 0
(1275 -25);
DISPLAY 0.978723 (1275 -25);
PAINT WHITE (1275 -25);
DISPLAY INVISIBLE (1275 -25);
FORCEADD Q_CAP..1
(1675 -175);
FORCEPROP 1 LAST PART_NUMBER CH647LME900
J 0
(1725 -325);
DISPLAY 0.638298 (1725 -325);
DISPLAY INVISIBLE (1725 -325);
FORCEPROP 1 LAST VOLTAGE 2.5V
J 0
(1725 -175);
DISPLAY 0.638298 (1725 -175);
FORCEPROP 1 LAST VALUE 47UF
J 0
(1725 -125);
DISPLAY 0.638298 (1725 -125);
FORCEPROP 1 LAST TOLERANCE 20%
J 0
(1725 -225);
DISPLAY 0.638298 (1725 -225);
FORCEPROP 1 LAST PACK_TYPE C0603
J 0
(1725 -375);
DISPLAY 0.638298 (1725 -375);
FORCEPROP 1 LAST MATERIAL X6S
J 0
(1725 -275);
DISPLAY 0.638298 (1725 -275);
FORCEPROP 1 LAST $LOCATION C1407
J 0
(1725 -75);
DISPLAY 0.978723 (1725 -75);
FORCEPROP 1 LASTPIN (1675 -75) $PN 1
J 0
(1685 -95);
DISPLAY 0.787234 (1685 -95);
FORCEPROP 1 LASTPIN (1675 -275) $PN 2
J 0
(1685 -295);
DISPLAY 0.787234 (1685 -295);
FORCEPROP 2 LAST CDS_LIB pure_quanta
J 0
(1675 -175);
PAINT MONO (1675 -175);
DISPLAY INVISIBLE (1675 -175);
FORCEPROP 2 LAST CDS_LOCATION C1407
J 0
(1725 25);
DISPLAY 1.021277 (1725 25);
DISPLAY INVISIBLE (1725 25);
FORCEPROP 2 LAST $SEC 1
J 0
(1725 25);
DISPLAY 0.680851 (1725 25);
PAINT MONO (1725 25);
DISPLAY INVISIBLE (1725 25);
FORCEPROP 2 LAST CDS_SEC 1
J 0
(1725 25);
DISPLAY 1.021277 (1725 25);
DISPLAY INVISIBLE (1725 25);
FORCEPROP 1 LAST PATH I62
J 0
(1725 -25);
DISPLAY 0.978723 (1725 -25);
PAINT WHITE (1725 -25);
DISPLAY INVISIBLE (1725 -25);
FORCEADD UNIVERSAL_GND..1
(975 2100);
FORCEPROP 3 LASTPIN (975 2150) SIG_NAME GND\g
J 0
(985 2160);
DISPLAY 0.659574 (985 2160);
PAINT MONO (985 2160);
DISPLAY INVISIBLE (985 2160);
FORCEPROP 2 LAST CDS_LIB logical_power
J 0
(975 2100);
PAINT MONO (975 2100);
DISPLAY INVISIBLE (975 2100);
FORCEPROP 1 LAST HDL_POWER GND
J 1
(1000 2025);
DISPLAY 0.872340 (1000 2025);
PAINT GREEN (1000 2025);
DISPLAY INVISIBLE (1000 2025);
FORCEPROP 1 LAST PATH I63
J 0
(1050 2100);
DISPLAY 0.872340 (1050 2100);
PAINT AQUA (1050 2100);
DISPLAY INVISIBLE (1050 2100);
FORCEADD Q_CAP..1
(975 2450);
FORCEPROP 1 LAST PART_NUMBER CH647KMEA04
J 0
(1025 2300);
DISPLAY 0.638298 (1025 2300);
DISPLAY INVISIBLE (1025 2300);
FORCEPROP 1 LAST VALUE 47UF
J 0
(1025 2500);
DISPLAY 0.638298 (1025 2500);
FORCEPROP 1 LAST VOLTAGE 4V
J 0
(1025 2450);
DISPLAY 0.638298 (1025 2450);
FORCEPROP 1 LAST TOLERANCE 20%
J 0
(1025 2400);
DISPLAY 0.638298 (1025 2400);
FORCEPROP 1 LAST PACK_TYPE C0805
J 0
(1025 2250);
DISPLAY 0.638298 (1025 2250);
FORCEPROP 1 LAST MATERIAL X6S
J 0
(1025 2350);
DISPLAY 0.638298 (1025 2350);
FORCEPROP 1 LAST $LOCATION C363
J 0
(1025 2550);
DISPLAY 0.638298 (1025 2550);
FORCEPROP 1 LASTPIN (975 2550) $PN 1
J 0
(985 2530);
DISPLAY 0.787234 (985 2530);
FORCEPROP 1 LASTPIN (975 2350) $PN 2
J 0
(985 2330);
DISPLAY 0.787234 (985 2330);
FORCEPROP 2 LAST CDS_LIB pure_quanta
J 0
(975 2450);
PAINT MONO (975 2450);
DISPLAY INVISIBLE (975 2450);
FORCEPROP 0 LAST CDS_LOCATION C363
J 0
(1025 2600);
DISPLAY 1.021277 (1025 2600);
DISPLAY INVISIBLE (1025 2600);
FORCEPROP 2 LAST $SEC 1
J 0
(1025 2650);
DISPLAY 0.680851 (1025 2650);
PAINT MONO (1025 2650);
DISPLAY INVISIBLE (1025 2650);
FORCEPROP 2 LAST CDS_SEC 1
J 0
(1025 2650);
DISPLAY 1.021277 (1025 2650);
DISPLAY INVISIBLE (1025 2650);
FORCEPROP 1 LAST PATH I64
J 0
(1025 2600);
DISPLAY 0.978723 (1025 2600);
PAINT WHITE (1025 2600);
DISPLAY INVISIBLE (1025 2600);
FORCEADD UNIVERSAL_POWER..1
(1550 2700);
FORCEPROP 3 LASTPIN (1550 2650) SIG_NAME PVCCIN_CPU0\g
J 0
(1560 2660);
DISPLAY 0.659574 (1560 2660);
PAINT MONO (1560 2660);
DISPLAY INVISIBLE (1560 2660);
FORCEPROP 1 LAST HDL_POWER PVCCIN_CPU0
J 1
(1750 2750);
DISPLAY 0.872340 (1750 2750);
PAINT GREEN (1750 2750);
FORCEPROP 2 LAST CDS_LIB logical_power
J 0
(1550 2700);
DISPLAY INVISIBLE (1550 2700);
FORCEPROP 1 LAST PATH I65
J 0
(1600 2725);
DISPLAY 0.872340 (1600 2725);
PAINT AQUA (1600 2725);
DISPLAY INVISIBLE (1600 2725);
FORCEADD UNIVERSAL_GND..1
(2000 2075);
FORCEPROP 3 LASTPIN (2000 2125) SIG_NAME GND\g
J 0
(2010 2135);
DISPLAY 0.659574 (2010 2135);
PAINT MONO (2010 2135);
DISPLAY INVISIBLE (2010 2135);
FORCEPROP 2 LAST CDS_LIB logical_power
J 0
(2000 2075);
DISPLAY INVISIBLE (2000 2075);
FORCEPROP 1 LAST HDL_POWER GND
J 1
(2025 2000);
DISPLAY 0.872340 (2025 2000);
PAINT GREEN (2025 2000);
DISPLAY INVISIBLE (2025 2000);
FORCEPROP 1 LAST PATH I66
J 0
(2075 2075);
DISPLAY 0.872340 (2075 2075);
PAINT AQUA (2075 2075);
DISPLAY INVISIBLE (2075 2075);
FORCEADD Q_CAP..1
(2750 2425);
FORCEPROP 1 LAST PART_NUMBER CH647KMEA04
J 0
(2800 2275);
DISPLAY 0.638298 (2800 2275);
DISPLAY INVISIBLE (2800 2275);
FORCEPROP 1 LAST TOLERANCE 20%
J 0
(2800 2375);
DISPLAY 0.638298 (2800 2375);
FORCEPROP 1 LAST VOLTAGE 4V
J 0
(2800 2425);
DISPLAY 0.638298 (2800 2425);
FORCEPROP 1 LAST PACK_TYPE C0805
J 0
(2800 2225);
DISPLAY 0.638298 (2800 2225);
FORCEPROP 1 LAST VALUE 47UF
J 0
(2800 2475);
DISPLAY 0.638298 (2800 2475);
FORCEPROP 1 LAST MATERIAL X6S
J 0
(2800 2325);
DISPLAY 0.638298 (2800 2325);
FORCEPROP 1 LAST $LOCATION C381
J 0
(2800 2525);
DISPLAY 0.638298 (2800 2525);
FORCEPROP 1 LASTPIN (2750 2525) $PN 1
J 0
(2760 2505);
DISPLAY 0.787234 (2760 2505);
PAINT MONO (2760 2505);
FORCEPROP 1 LASTPIN (2750 2325) $PN 2
J 0
(2760 2305);
DISPLAY 0.787234 (2760 2305);
PAINT MONO (2760 2305);
FORCEPROP 2 LAST CDS_LIB pure_quanta
J 0
(2750 2425);
DISPLAY INVISIBLE (2750 2425);
FORCEPROP 2 LAST CDS_LOCATION C381
J 0
(2800 2625);
DISPLAY 1.021277 (2800 2625);
DISPLAY INVISIBLE (2800 2625);
FORCEPROP 0 LAST $SEC 1
J 0
(2800 2575);
DISPLAY 0.680851 (2800 2575);
PAINT MONO (2800 2575);
DISPLAY INVISIBLE (2800 2575);
FORCEPROP 2 LAST CDS_SEC 1
J 0
(2800 2625);
DISPLAY 1.021277 (2800 2625);
DISPLAY INVISIBLE (2800 2625);
FORCEPROP 1 LAST PATH I67
J 0
(2800 2575);
DISPLAY 0.978723 (2800 2575);
PAINT WHITE (2800 2575);
DISPLAY INVISIBLE (2800 2575);
FORCEADD Q_CAP..1
(3200 2425);
FORCEPROP 1 LAST PART_NUMBER CH647KMEA04
J 0
(3250 2275);
DISPLAY 0.638298 (3250 2275);
DISPLAY INVISIBLE (3250 2275);
FORCEPROP 1 LAST TOLERANCE 20%
J 0
(3250 2375);
DISPLAY 0.638298 (3250 2375);
FORCEPROP 1 LAST VOLTAGE 4V
J 0
(3250 2425);
DISPLAY 0.638298 (3250 2425);
FORCEPROP 1 LAST PACK_TYPE C0805
J 0
(3250 2225);
DISPLAY 0.638298 (3250 2225);
FORCEPROP 1 LAST MATERIAL X6S
J 0
(3250 2325);
DISPLAY 0.638298 (3250 2325);
FORCEPROP 1 LAST VALUE 47UF
J 0
(3250 2475);
DISPLAY 0.638298 (3250 2475);
FORCEPROP 1 LAST $LOCATION C527
J 0
(3250 2525);
DISPLAY 0.638298 (3250 2525);
FORCEPROP 1 LASTPIN (3200 2525) $PN 1
J 0
(3210 2505);
DISPLAY 0.787234 (3210 2505);
PAINT MONO (3210 2505);
FORCEPROP 1 LASTPIN (3200 2325) $PN 2
J 0
(3210 2305);
DISPLAY 0.787234 (3210 2305);
PAINT MONO (3210 2305);
FORCEPROP 2 LAST CDS_LIB pure_quanta
J 0
(3200 2425);
DISPLAY INVISIBLE (3200 2425);
FORCEPROP 2 LAST CDS_LOCATION C527
J 0
(3250 2625);
DISPLAY 1.021277 (3250 2625);
DISPLAY INVISIBLE (3250 2625);
FORCEPROP 0 LAST $SEC 1
J 0
(3250 2575);
DISPLAY 0.680851 (3250 2575);
PAINT MONO (3250 2575);
DISPLAY INVISIBLE (3250 2575);
FORCEPROP 2 LAST CDS_SEC 1
J 0
(3250 2625);
DISPLAY 1.021277 (3250 2625);
DISPLAY INVISIBLE (3250 2625);
FORCEPROP 1 LAST PATH I68
J 0
(3250 2575);
DISPLAY 0.978723 (3250 2575);
PAINT WHITE (3250 2575);
DISPLAY INVISIBLE (3250 2575);
FORCEADD UNIVERSAL_GND..1
(-3075 -1575);
FORCEPROP 3 LASTPIN (-3075 -1525) SIG_NAME GND\g
J 0
(-3065 -1515);
DISPLAY 0.659574 (-3065 -1515);
PAINT MONO (-3065 -1515);
DISPLAY INVISIBLE (-3065 -1515);
FORCEPROP 2 LAST CDS_LIB logical_power
J 0
(-3075 -1575);
PAINT MONO (-3075 -1575);
DISPLAY INVISIBLE (-3075 -1575);
FORCEPROP 1 LAST HDL_POWER GND
J 1
(-3050 -1650);
DISPLAY 0.872340 (-3050 -1650);
PAINT GREEN (-3050 -1650);
DISPLAY INVISIBLE (-3050 -1650);
FORCEPROP 1 LAST PATH I7
J 0
(-3000 -1575);
DISPLAY 0.872340 (-3000 -1575);
PAINT AQUA (-3000 -1575);
DISPLAY INVISIBLE (-3000 -1575);
FORCEADD Q_CAP..1
(-2625 -2225);
FORCEPROP 1 LAST PART_NUMBER CH647LME900
J 0
(-2575 -2375);
DISPLAY 0.638298 (-2575 -2375);
DISPLAY INVISIBLE (-2575 -2375);
FORCEPROP 1 LAST PACK_TYPE C0603
J 0
(-2575 -2425);
DISPLAY 0.638298 (-2575 -2425);
FORCEPROP 1 LAST VOLTAGE 2.5V
J 0
(-2575 -2225);
DISPLAY 0.638298 (-2575 -2225);
FORCEPROP 1 LAST VALUE 47UF
J 0
(-2575 -2175);
DISPLAY 0.638298 (-2575 -2175);
FORCEPROP 1 LAST TOLERANCE 20%
J 0
(-2575 -2275);
DISPLAY 0.638298 (-2575 -2275);
FORCEPROP 1 LAST MATERIAL X6S
J 0
(-2575 -2325);
DISPLAY 0.638298 (-2575 -2325);
FORCEPROP 1 LAST $LOCATION C509
J 0
(-2575 -2125);
DISPLAY 0.978723 (-2575 -2125);
FORCEPROP 1 LASTPIN (-2625 -2125) $PN 1
J 0
(-2615 -2145);
DISPLAY 0.787234 (-2615 -2145);
FORCEPROP 1 LASTPIN (-2625 -2325) $PN 2
J 0
(-2615 -2345);
DISPLAY 0.787234 (-2615 -2345);
FORCEPROP 2 LAST CDS_LIB pure_quanta
J 0
(-2625 -2225);
PAINT MONO (-2625 -2225);
DISPLAY INVISIBLE (-2625 -2225);
FORCEPROP 2 LAST CDS_LOCATION C509
J 0
(-2575 -2025);
DISPLAY 1.021277 (-2575 -2025);
DISPLAY INVISIBLE (-2575 -2025);
FORCEPROP 2 LAST $SEC 1
J 0
(-2575 -2025);
DISPLAY 0.680851 (-2575 -2025);
PAINT MONO (-2575 -2025);
DISPLAY INVISIBLE (-2575 -2025);
FORCEPROP 2 LAST CDS_SEC 1
J 0
(-2575 -2025);
DISPLAY 1.021277 (-2575 -2025);
DISPLAY INVISIBLE (-2575 -2025);
FORCEPROP 1 LAST PATH I8
J 0
(-2575 -2075);
DISPLAY 0.978723 (-2575 -2075);
PAINT WHITE (-2575 -2075);
DISPLAY INVISIBLE (-2575 -2075);
FORCEADD Q_CAP..1
(-4425 -1225);
FORCEPROP 1 LAST PART_NUMBER CH647KMEA04
J 0
(-4375 -1375);
DISPLAY 0.638298 (-4375 -1375);
DISPLAY INVISIBLE (-4375 -1375);
FORCEPROP 1 LAST PACK_TYPE C0805
J 0
(-4375 -1425);
DISPLAY 0.638298 (-4375 -1425);
FORCEPROP 1 LAST TOLERANCE 20%
J 0
(-4375 -1275);
DISPLAY 0.638298 (-4375 -1275);
FORCEPROP 1 LAST MATERIAL X6S
J 0
(-4375 -1325);
DISPLAY 0.638298 (-4375 -1325);
FORCEPROP 1 LAST VOLTAGE 4V
J 0
(-4375 -1225);
DISPLAY 0.638298 (-4375 -1225);
FORCEPROP 1 LAST VALUE 47UF
J 0
(-4375 -1175);
DISPLAY 0.638298 (-4375 -1175);
FORCEPROP 1 LAST $LOCATION C522
J 0
(-4375 -1125);
DISPLAY 0.978723 (-4375 -1125);
FORCEPROP 1 LASTPIN (-4425 -1125) $PN 1
J 0
(-4415 -1145);
DISPLAY 0.787234 (-4415 -1145);
FORCEPROP 1 LASTPIN (-4425 -1325) $PN 2
J 0
(-4415 -1345);
DISPLAY 0.787234 (-4415 -1345);
FORCEPROP 2 LAST CDS_LIB pure_quanta
J 0
(-4425 -1225);
PAINT MONO (-4425 -1225);
DISPLAY INVISIBLE (-4425 -1225);
FORCEPROP 2 LAST CDS_LOCATION C522
J 0
(-4375 -1025);
DISPLAY 1.021277 (-4375 -1025);
DISPLAY INVISIBLE (-4375 -1025);
FORCEPROP 2 LAST $SEC 1
J 0
(-4375 -1025);
DISPLAY 0.680851 (-4375 -1025);
PAINT MONO (-4375 -1025);
DISPLAY INVISIBLE (-4375 -1025);
FORCEPROP 2 LAST CDS_SEC 1
J 0
(-4375 -1025);
DISPLAY 1.021277 (-4375 -1025);
DISPLAY INVISIBLE (-4375 -1025);
FORCEPROP 1 LAST PATH I9
J 0
(-4375 -1075);
DISPLAY 0.978723 (-4375 -1075);
PAINT WHITE (-4375 -1075);
DISPLAY INVISIBLE (-4375 -1075);
FORCEADD QUANTA_TITLE_BLOCK_C..1
(4625 -3425);
FORCEPROP 0 LAST CDS_CON_LAST_MODIFIED Fri Aug 25 14:00:55 2023
J 0
(2740 -3410);
PAINT MONO (2740 -3410);
DISPLAY INVISIBLE (2740 -3410);
FORCEPROP 2 LAST CUSTOM_TXT_CDS <XR_PAGE_TITLE>
J 0
(-3265 1825);
DISPLAY 0.638298 (-3265 1825);
PAINT PINK (-3265 1825);
DISPLAY INVISIBLE (-3265 1825);
FORCEPROP 2 LAST CUSTOM_TXT_CDS <Q_NUMBER>
J 0
(3222 -3322);
DISPLAY 1.212766 (3222 -3322);
FORCEPROP 2 LAST CUSTOM_TXT_CDS <CON_LAST_MODIFIED>
J 0
(2740 -3410);
DISPLAY 0.978723 (2740 -3410);
FORCEPROP 2 LAST CUSTOM_TXT_CDS <CON_PAGE_NUM> OF <CON_TOTAL_PAGES>
J 0
(4175 -3425);
DISPLAY 0.978723 (4175 -3425);
FORCEPROP 2 LAST CUSTOM_TXT_CDS <Q_REV>
J 0
(4441 -3322);
DISPLAY 1.212766 (4441 -3322);
FORCEPROP 2 LAST CUSTOM_TXT_CDS <NAME_2>
J 0
(1450 -3375);
FORCEPROP 2 LAST CUSTOM_TXT_CDS <NAME_1>
J 0
(1450 -3250);
FORCEPROP 2 LAST CUSTOM_TXT_CDS <Q_PROJ>
J 0
(2243 -3323);
DISPLAY 1.212766 (2243 -3323);
FORCEPROP 1 LAST Q_TITLE SPR CPU0 BOTTOM DECOUPLING CAPS
J 0
(-4716 -3399);
DISPLAY 1.957447 (-4716 -3399);
PAINT GREEN (-4716 -3399);
FORCEPROP 1 LAST Q_DEPT 
J 1
(862 -3376);
DISPLAY 1.957447 (862 -3376);
PAINT GREEN (862 -3376);
FORCEPROP 1 LAST COMMENT_BODY TRUE
J 0
(4637 -3438);
DISPLAY 0.978723 (4637 -3438);
PAINT GREEN (4637 -3438);
DISPLAY INVISIBLE (4637 -3438);
FORCEPROP 2 LAST CDS_XR_PAGE_TITLE CR-75 : @S9S_MB_2U_LIB.S9S_MB_2U(SCH_1):PAGE75
J 0
(-3265 1825);
DISPLAY 0.638298 (-3265 1825);
PAINT PINK (-3265 1825);
DISPLAY INVISIBLE (-3265 1825);
FORCEPROP 2 LAST CDS_LIB pure_quanta
J 0
(4625 -3425);
PAINT MONO (4625 -3425);
DISPLAY INVISIBLE (4625 -3425);
FORCEPROP 1 LAST CDS_LMAN_SYM_OUTLINE -9475,6775,100,-125
J 0
(4625 -3425);
DISPLAY 0.468085 (4625 -3425);
PAINT GREEN (4625 -3425);
DISPLAY INVISIBLE (4625 -3425);
FORCEPROP 2 LAST PAGE_BORDER TRUE
J 0
(-3265 1825);
DISPLAY 0.638298 (-3265 1825);
PAINT PINK (-3265 1825);
DISPLAY INVISIBLE (-3265 1825);
WIRE 16 -1 (-4425 -1050)(-4425 -1000);
WIRE 16 -1 (-3975 -1050)(-4425 -1050);
WIRE 16 -1 (-4425 -1050)(-4425 -1125);
WIRE 16 -1 (-4425 -75)(-4425 -25);
WIRE 16 -1 (-3975 -75)(-4425 -75);
WIRE 16 -1 (-4425 -75)(-4425 -150);
WIRE 16 -1 (-4425 -2050)(-4425 -2000);
WIRE 16 -1 (-3975 -2050)(-4425 -2050);
WIRE 16 -1 (-4425 -2050)(-4425 -2125);
WIRE 16 -1 (-4425 900)(-4425 950);
WIRE 16 -1 (-3975 900)(-4425 900);
WIRE 16 -1 (-4425 900)(-4425 825);
WIRE 16 -1 (-4425 1900)(-4425 1950);
WIRE 16 -1 (-3975 1900)(-4425 1900);
WIRE 16 -1 (-4425 1900)(-4425 1825);
WIRE 16 -1 (-4425 2625)(-4425 2675);
WIRE 16 -1 (-3975 2625)(-4425 2625);
WIRE 16 -1 (-4425 2625)(-4425 2550);
WIRE 16 -1 (325 -1050)(325 -1000);
WIRE 16 -1 (775 -1050)(325 -1050);
WIRE 16 -1 (325 -1050)(325 -1125);
WIRE 16 -1 (325 0)(325 50);
WIRE 16 -1 (775 0)(325 0);
WIRE 16 -1 (325 0)(325 -75);
WIRE 16 -1 (1550 2650)(1550 2600);
WIRE 16 -1 (-2625 -2525)(-2625 -2450);
WIRE 16 -1 (-3075 -1525)(-3075 -1450);
WIRE 16 -1 (-3975 -550)(-3975 -475);
WIRE 16 -1 (-3075 450)(-3075 500);
WIRE 16 -1 (525 1425)(525 1500);
WIRE 16 -1 (1675 -1525)(1675 -1450);
WIRE 16 -1 (1675 -475)(1675 -400);
WIRE 16 -1 (975 2150)(975 2225);
WIRE 16 -1 (2000 2125)(2000 2175);
WIRE 16 -1 (325 -1450)(325 -1325);
WIRE 16 -1 (775 -1450)(325 -1450);
WIRE 16 -1 (775 -1450)(775 -1325);
WIRE 16 -1 (1225 -1450)(775 -1450);
WIRE 16 -1 (1225 -1450)(1225 -1325);
WIRE 16 -1 (1675 -1450)(1225 -1450);
WIRE 16 -1 (1675 -1450)(1675 -1325);
WIRE 16 -1 (-3975 -2125)(-3975 -2050);
WIRE 16 -1 (-3525 -2050)(-3975 -2050);
WIRE 16 -1 (-3525 -2050)(-3525 -2125);
WIRE 16 -1 (-3075 -2050)(-3525 -2050);
WIRE 16 -1 (-3075 -2125)(-3075 -2050);
WIRE 16 -1 (-2625 -2050)(-3075 -2050);
WIRE 16 -1 (-2625 -2125)(-2625 -2050);
WIRE 16 -1 (-4425 -1450)(-4425 -1325);
WIRE 16 -1 (-3975 -1450)(-4425 -1450);
WIRE 16 -1 (-3975 -1450)(-3975 -1325);
WIRE 16 -1 (-3525 -1450)(-3975 -1450);
WIRE 16 -1 (-3525 -1450)(-3525 -1325);
WIRE 16 -1 (-3075 -1450)(-3525 -1450);
WIRE 16 -1 (-3075 -1450)(-3075 -1325);
WIRE 16 -1 (-3975 -1050)(-3975 -1125);
WIRE 16 -1 (-3525 -1050)(-3975 -1050);
WIRE 16 -1 (-3525 -1125)(-3525 -1050);
WIRE 16 -1 (-3075 -1050)(-3525 -1050);
WIRE 16 -1 (-3075 -1050)(-3075 -1125);
WIRE 16 -1 (-3975 -150)(-3975 -75);
WIRE 16 -1 (2750 2600)(1550 2600);
WIRE 16 -1 (2750 2600)(2750 2525);
WIRE 16 -1 (3200 2600)(2750 2600);
WIRE 16 -1 (3200 2525)(3200 2600);
WIRE 16 -1 (2750 2175)(2000 2175);
WIRE 16 -1 (2750 2175)(2750 2325);
WIRE 16 -1 (3200 2175)(2750 2175);
WIRE 16 -1 (3200 2175)(3200 2325);
WIRE 16 -1 (775 -75)(775 0);
WIRE 16 -1 (775 0)(1225 0);
WIRE 16 -1 (1225 0)(1225 -75);
WIRE 16 -1 (1675 0)(1225 0);
WIRE 16 -1 (1675 -75)(1675 0);
WIRE 16 -1 (775 -1125)(775 -1050);
WIRE 16 -1 (1225 -1050)(775 -1050);
WIRE 16 -1 (1225 -1050)(1225 -1125);
WIRE 16 -1 (1675 -1050)(1225 -1050);
WIRE 16 -1 (1675 -1050)(1675 -1125);
WIRE 16 -1 (325 -400)(325 -275);
WIRE 16 -1 (775 -400)(325 -400);
WIRE 16 -1 (775 -400)(775 -275);
WIRE 16 -1 (1225 -400)(775 -400);
WIRE 16 -1 (1225 -400)(1225 -275);
WIRE 16 -1 (1675 -400)(1225 -400);
WIRE 16 -1 (1675 -400)(1675 -275);
WIRE 16 -1 (-3975 2550)(-3975 2625);
WIRE 16 -1 (-3525 2625)(-3975 2625);
WIRE 16 -1 (-3525 2625)(-3525 2550);
WIRE 16 -1 (-3075 2550)(-3075 2625);
WIRE 16 -1 (-3075 2625)(-3525 2625);
WIRE 16 -1 (-2625 2625)(-3075 2625);
WIRE 16 -1 (-2625 2550)(-2625 2625);
WIRE 16 -1 (-2175 2625)(-2625 2625);
WIRE 16 -1 (-2175 2625)(-2175 2550);
WIRE 16 -1 (-1725 2625)(-2175 2625);
WIRE 16 -1 (-1725 2550)(-1725 2625);
WIRE 16 -1 (-1275 2625)(-1725 2625);
WIRE 16 -1 (-1275 2550)(-1275 2625);
WIRE 16 -1 (-825 2625)(-1275 2625);
WIRE 16 -1 (-825 2625)(-825 2550);
WIRE 16 -1 (-375 2625)(-825 2625);
WIRE 16 -1 (-375 2550)(-375 2625);
WIRE 16 -1 (75 2625)(-375 2625);
WIRE 16 -1 (75 2625)(75 2550);
WIRE 16 -1 (525 2625)(75 2625);
WIRE 16 -1 (525 2550)(525 2625);
WIRE 16 -1 (975 2625)(525 2625);
WIRE 16 -1 (975 2550)(975 2625);
WIRE 16 -1 (-4425 2225)(-4425 2350);
WIRE 16 -1 (-3975 2225)(-4425 2225);
WIRE 16 -1 (-3975 2225)(-3975 2350);
WIRE 16 -1 (-3525 2225)(-3975 2225);
WIRE 16 -1 (-3525 2225)(-3525 2350);
WIRE 16 -1 (-3075 2225)(-3525 2225);
WIRE 16 -1 (-3075 2225)(-3075 2350);
WIRE 16 -1 (-2625 2225)(-3075 2225);
WIRE 16 -1 (-2625 2225)(-2625 2350);
WIRE 16 -1 (-2175 2225)(-2625 2225);
WIRE 16 -1 (-2175 2225)(-2175 2350);
WIRE 16 -1 (-1725 2225)(-2175 2225);
WIRE 16 -1 (-1725 2225)(-1725 2350);
WIRE 16 -1 (-1275 2225)(-1725 2225);
WIRE 16 -1 (-1275 2225)(-1275 2350);
WIRE 16 -1 (-825 2225)(-1275 2225);
WIRE 16 -1 (-825 2225)(-825 2350);
WIRE 16 -1 (-375 2225)(-825 2225);
WIRE 16 -1 (-375 2225)(-375 2350);
WIRE 16 -1 (75 2225)(-375 2225);
WIRE 16 -1 (75 2225)(75 2350);
WIRE 16 -1 (525 2225)(75 2225);
WIRE 16 -1 (525 2225)(525 2350);
WIRE 16 -1 (975 2225)(525 2225);
WIRE 16 -1 (975 2225)(975 2350);
WIRE 16 -1 (-3975 1825)(-3975 1900);
WIRE 16 -1 (-3525 1900)(-3975 1900);
WIRE 16 -1 (-3525 1900)(-3525 1825);
WIRE 16 -1 (-3075 1900)(-3525 1900);
WIRE 16 -1 (-3075 1825)(-3075 1900);
WIRE 16 -1 (-2625 1900)(-3075 1900);
WIRE 16 -1 (-2625 1825)(-2625 1900);
WIRE 16 -1 (-2175 1900)(-2625 1900);
WIRE 16 -1 (-2175 1900)(-2175 1825);
WIRE 16 -1 (-1725 1900)(-2175 1900);
WIRE 16 -1 (-1725 1825)(-1725 1900);
WIRE 16 -1 (-1275 1900)(-1725 1900);
WIRE 16 -1 (-1275 1825)(-1275 1900);
WIRE 16 -1 (-825 1900)(-1275 1900);
WIRE 16 -1 (-825 1900)(-825 1825);
WIRE 16 -1 (-375 1900)(-825 1900);
WIRE 16 -1 (-375 1825)(-375 1900);
WIRE 16 -1 (75 1900)(-375 1900);
WIRE 16 -1 (75 1825)(75 1900);
WIRE 16 -1 (525 1900)(75 1900);
WIRE 16 -1 (525 1825)(525 1900);
WIRE 16 -1 (-4425 1500)(-4425 1625);
WIRE 16 -1 (-3975 1500)(-4425 1500);
WIRE 16 -1 (-3975 1500)(-3975 1625);
WIRE 16 -1 (-3525 1500)(-3975 1500);
WIRE 16 -1 (-3525 1500)(-3525 1625);
WIRE 16 -1 (-3075 1500)(-3525 1500);
WIRE 16 -1 (-3075 1500)(-3075 1625);
WIRE 16 -1 (-2625 1500)(-3075 1500);
WIRE 16 -1 (-2625 1500)(-2625 1625);
WIRE 16 -1 (-2175 1500)(-2625 1500);
WIRE 16 -1 (-2175 1500)(-2175 1625);
WIRE 16 -1 (-1725 1500)(-2175 1500);
WIRE 16 -1 (-1725 1500)(-1725 1625);
WIRE 16 -1 (-1275 1500)(-1725 1500);
WIRE 16 -1 (-1275 1500)(-1275 1625);
WIRE 16 -1 (-825 1500)(-1275 1500);
WIRE 16 -1 (-825 1500)(-825 1625);
WIRE 16 -1 (-375 1500)(-825 1500);
WIRE 16 -1 (-375 1500)(-375 1625);
WIRE 16 -1 (75 1500)(-375 1500);
WIRE 16 -1 (75 1500)(75 1625);
WIRE 16 -1 (525 1500)(75 1500);
WIRE 16 -1 (525 1500)(525 1625);
WIRE 16 -1 (-4425 500)(-4425 625);
WIRE 16 -1 (-3075 625)(-3075 500);
WIRE 16 -1 (-3975 500)(-4425 500);
WIRE 16 -1 (-3975 500)(-3975 625);
WIRE 16 -1 (-3525 500)(-3975 500);
WIRE 16 -1 (-3075 500)(-3525 500);
WIRE 16 -1 (-3525 625)(-3525 500);
WIRE 16 -1 (-3975 825)(-3975 900);
WIRE 16 -1 (-3525 900)(-3975 900);
WIRE 16 -1 (-3525 825)(-3525 900);
WIRE 16 -1 (-3075 900)(-3525 900);
WIRE 16 -1 (-3075 825)(-3075 900);
WIRE 16 -1 (-4425 -475)(-4425 -350);
WIRE 16 -1 (-3975 -475)(-4425 -475);
WIRE 16 -1 (-3975 -475)(-3975 -350);
WIRE 16 -1 (-4425 -2450)(-4425 -2325);
WIRE 16 -1 (-3975 -2450)(-4425 -2450);
WIRE 16 -1 (-3975 -2450)(-3975 -2325);
WIRE 16 -1 (-3525 -2450)(-3975 -2450);
WIRE 16 -1 (-3525 -2450)(-3525 -2325);
WIRE 16 -1 (-3075 -2450)(-3525 -2450);
WIRE 16 -1 (-3075 -2450)(-3075 -2325);
WIRE 16 -1 (-2625 -2450)(-2625 -2325);
WIRE 16 -1 (-2625 -2450)(-3075 -2450);
DOT 1 (2750 2600);
DOT 1 (2750 2175);
DOT 1 (975 2225);
DOT 1 (1225 0);
DOT 1 (1675 -400);
DOT 1 (1225 -400);
DOT 1 (1225 -1050);
DOT 1 (1675 -1450);
DOT 1 (1225 -1450);
DOT 1 (525 2625);
DOT 1 (525 2225);
DOT 1 (75 2625);
DOT 1 (75 2225);
DOT 1 (75 1900);
DOT 1 (525 1500);
DOT 1 (75 1500);
DOT 1 (-375 2625);
DOT 1 (-375 2225);
DOT 1 (-375 1900);
DOT 1 (-825 2625);
DOT 1 (-825 2225);
DOT 1 (-825 1900);
DOT 1 (-375 1500);
DOT 1 (-825 1500);
DOT 1 (775 0);
DOT 1 (325 0);
DOT 1 (775 -400);
DOT 1 (775 -1050);
DOT 1 (325 -1050);
DOT 1 (-1275 2625);
DOT 1 (-1275 2225);
DOT 1 (-1275 1900);
DOT 1 (-1725 1900);
DOT 1 (-1725 2225);
DOT 1 (-1725 2625);
DOT 1 (-2175 2625);
DOT 1 (-2175 2225);
DOT 1 (-2175 1900);
DOT 1 (-1275 1500);
DOT 1 (-1725 1500);
DOT 1 (-2175 1500);
DOT 1 (-2625 2625);
DOT 1 (-2625 2225);
DOT 1 (-2625 1900);
DOT 1 (-3075 2625);
DOT 1 (-3075 2225);
DOT 1 (-3075 1900);
DOT 1 (-2625 1500);
DOT 1 (-3075 1500);
DOT 1 (-3075 500);
DOT 1 (-3525 2625);
DOT 1 (-3525 2225);
DOT 1 (-3525 1900);
DOT 1 (-3975 2625);
DOT 1 (-3975 2225);
DOT 1 (-3975 1900);
DOT 1 (-3525 1500);
DOT 1 (-3525 900);
DOT 1 (-3975 1500);
DOT 1 (-3975 900);
DOT 1 (-4425 2625);
DOT 1 (-4425 1900);
DOT 1 (-4425 900);
DOT 1 (-3525 500);
DOT 1 (-3975 500);
DOT 1 (-3525 -1050);
DOT 1 (-3975 -475);
DOT 1 (-3975 -1050);
DOT 1 (-4425 -75);
DOT 1 (-4425 -1050);
DOT 1 (775 -1450);
DOT 1 (-3075 -1450);
DOT 1 (-3075 -2050);
DOT 1 (-2625 -2450);
DOT 1 (-3075 -2450);
DOT 1 (-3525 -1450);
DOT 1 (-3525 -2050);
DOT 1 (-3975 -1450);
DOT 1 (-3975 -2050);
DOT 1 (-3525 -2450);
DOT 1 (-3975 -2450);
DOT 1 (-4425 -2050);
FORCENOTE
PVCCIN: 1 0805 47UF CAPS PLACED AT CAVITY(LEFT)
(2100 2750) 0;
DISPLAY LEFT (2100 2750);
DISPLAY 0.808511 (2100 2750);
PAINT SKYBLUE (2100 2750);
FORCENOTE
PVCCIN: 1 0805 47UF CAPS PLACED AT CAVITY(RIGHT)
(2100 2650) 0;
DISPLAY LEFT (2100 2650);
DISPLAY 0.808511 (2100 2650);
PAINT SKYBLUE (2100 2650);
FORCENOTE
PVNN_MAIN: 4 CAPS PLACED AT CAVITY(RIGHT)
(875 50) 0;
DISPLAY LEFT (875 50);
DISPLAY 0.808511 (875 50);
PAINT SKYBLUE (875 50);
FORCENOTE
PVNN_MAIN: 4 CAPS PLACED AT CAVITY(LEFT)
(-4325 -1000) 0;
DISPLAY LEFT (-4325 -1000);
DISPLAY 0.808511 (-4325 -1000);
PAINT SKYBLUE (-4325 -1000);
FORCENOTE
PVCCIN: 12 0805 100UF CAPS PLACED AT CAVITY(RIGHT)
(-3525 1975) 0;
DISPLAY LEFT (-3525 1975);
DISPLAY 0.808511 (-3525 1975);
PAINT SKYBLUE (-3525 1975);
FORCENOTE
PVCCD_HV: 1 100UF CAP & 1 47UF CAP ARE PLACED AT CAVITY(LEFT)
(-3750 1050) 0;
DISPLAY LEFT (-3750 1050);
DISPLAY 0.808511 (-3750 1050);
PAINT SKYBLUE (-3750 1050);
FORCENOTE
PVCCD_HV: 1 100UF CAP & 1 47UF CAP ARE PLACED AT CAVITY(RIGHT)
(-3750 975) 0;
DISPLAY LEFT (-3750 975);
DISPLAY 0.808511 (-3750 975);
PAINT SKYBLUE (-3750 975);
FORCENOTE
PVCCFA_EHV: 2 100UF CAPS PLACED AT CAVITY(LEFT)
(-4321 -29) 0;
DISPLAY LEFT (-4321 -29);
DISPLAY 0.808511 (-4321 -29);
PAINT SKYBLUE (-4321 -29);
FORCENOTE
PVCCIN: 13 0805 100UF CAPS PLACED AT CAVITY(LEFT)
(-3525 2700) 0;
DISPLAY LEFT (-3525 2700);
DISPLAY 0.808511 (-3525 2700);
PAINT SKYBLUE (-3525 2700);
FORCENOTE
PVCCD_HV: 2 100UF CAPS ARE PLACED AT CAVITY(RIGHT)
(-3500 -1975) 0;
DISPLAY LEFT (-3500 -1975);
DISPLAY 0.808511 (-3500 -1975);
PAINT SKYBLUE (-3500 -1975);
FORCENOTE
PVCCD_HV: 2 100UF CAP & 1 47UF CAP ARE PLACED AT CAVITY(LEFT)
(-3500 -1900) 0;
DISPLAY LEFT (-3500 -1900);
DISPLAY 0.808511 (-3500 -1900);
PAINT SKYBLUE (-3500 -1900);
QUIT
